FILE_TYPE = MACRO_DRAWING;
SET COLOR_WIRE YELLOW;
SET COLOR_PROP ORANGE;
SET COLOR_DOT WHITE;
SET COLOR_ARC YELLOW;
SET COLOR_BODY GREEN;
SET COLOR_NOTE PURPLE;
SET PROP_DISPLAY VALUE;
SET PAGE_NUMBER P201;
FORCEADD OFFPAGE..1
(-8525 4000);
FORCEPROP 2 LAST $XR0 81 
J 0
(-8776 4000);
DISPLAY 0.638298 (-8776 4000);
PAINT MONO (-8776 4000);
FORCEPROP 2 LAST CDS_LIB standard
J 0
(-8525 4000);
DISPLAY INVISIBLE (-8525 4000);
FORCEPROP 1 LAST OFFPAGE TRUE
J 0
(-8200 3875);
DISPLAY 0.872340 (-8200 3875);
PAINT GREEN (-8200 3875);
DISPLAY INVISIBLE (-8200 3875);
FORCEPROP 1 LAST COMMENT_BODY TRUE
J 0
(-8400 3900);
DISPLAY 0.872340 (-8400 3900);
PAINT GREEN (-8400 3900);
DISPLAY INVISIBLE (-8400 3900);
FORCEPROP 2 LAST PATH I1
J 0
(-8725 4050);
DISPLAY 0.680851 (-8725 4050);
DISPLAY INVISIBLE (-8725 4050);
FORCEADD UNIVERSAL_GND..1
(-6375 2725);
FORCEPROP 3 LASTPIN (-6375 2775) SIG_NAME GND\g
J 0
(-6365 2785);
DISPLAY 0.659574 (-6365 2785);
PAINT MONO (-6365 2785);
DISPLAY INVISIBLE (-6365 2785);
FORCEPROP 2 LAST CDS_LIB pure_quanta_power
J 0
(-6375 2725);
DISPLAY INVISIBLE (-6375 2725);
FORCEPROP 1 LAST HDL_POWER GND
J 1
(-6350 2650);
DISPLAY 0.872340 (-6350 2650);
PAINT GREEN (-6350 2650);
DISPLAY INVISIBLE (-6350 2650);
FORCEPROP 1 LAST PATH I10
J 0
(-6300 2725);
DISPLAY 0.872340 (-6300 2725);
PAINT AQUA (-6300 2725);
DISPLAY INVISIBLE (-6300 2725);
FORCEADD Q_RES..2
(-6375 2975);
FORCEPROP 1 LAST LOCATION PR8
J 0
(-6330 3100);
DISPLAY 0.489362 (-6330 3100);
PAINT SKYBLUE (-6330 3100);
FORCEPROP 2 LAST SEC 1
J 0
(-6313 3218);
DISPLAY 0.680851 (-6313 3218);
PAINT MONO (-6313 3218);
DISPLAY INVISIBLE (-6313 3218);
FORCEPROP 1 LASTPIN (-6375 3075) $PN 1
J 0
(-6370 3037);
DISPLAY 0.489362 (-6370 3037);
FORCEPROP 1 LASTPIN (-6375 2875) $PN 2
J 0
(-6370 2885);
DISPLAY 0.489362 (-6370 2885);
FORCEPROP 1 LAST PACK_TYPE 0402LF
J 0
(-6335 2800);
DISPLAY 0.489362 (-6335 2800);
PAINT SKYBLUE (-6335 2800);
FORCEPROP 1 LAST WATTAGE 1/16W
J 0
(-6335 2950);
DISPLAY 0.489362 (-6335 2950);
PAINT SKYBLUE (-6335 2950);
FORCEPROP 1 LAST MATERIAL CHIP
J 0
(-6335 2900);
DISPLAY 0.489362 (-6335 2900);
PAINT SKYBLUE (-6335 2900);
FORCEPROP 1 LAST TOLERANCE 1%
J 0
(-6330 3000);
DISPLAY 0.489362 (-6330 3000);
PAINT SKYBLUE (-6330 3000);
FORCEPROP 1 LAST VALUE 8.66K
J 0
(-6330 3050);
DISPLAY 0.489362 (-6330 3050);
PAINT SKYBLUE (-6330 3050);
FORCEPROP 2 LAST CDS_LIB pure_quanta
R 3
J 0
(-6375 2975);
DISPLAY INVISIBLE (-6375 2975);
FORCEPROP 2 LAST SEC_TYPE 0402LF
J 0
(-6313 3218);
DISPLAY 1.021277 (-6313 3218);
DISPLAY INVISIBLE (-6313 3218);
FORCEPROP 1 LAST PATH I11
J 0
(-6325 3150);
DISPLAY 0.978723 (-6325 3150);
PAINT WHITE (-6325 3150);
DISPLAY INVISIBLE (-6325 3150);
FORCEPROP 1 LAST PART_NUMBER CS28662FB02
J 0
(-6335 2850);
DISPLAY 0.489362 (-6335 2850);
PAINT SKYBLUE (-6335 2850);
DISPLAY INVISIBLE (-6335 2850);
FORCEADD Q_RES..2
(-6875 3400);
FORCEPROP 1 LAST LOCATION PR397
J 0
(-6830 3525);
DISPLAY 0.489362 (-6830 3525);
PAINT SKYBLUE (-6830 3525);
FORCEPROP 0 LAST $SEC 1
J 0
(-6825 3575);
DISPLAY 0.680851 (-6825 3575);
PAINT MONO (-6825 3575);
DISPLAY INVISIBLE (-6825 3575);
FORCEPROP 0 LAST CDS_SEC 1
J 0
(-6825 3575);
DISPLAY 1.021277 (-6825 3575);
DISPLAY INVISIBLE (-6825 3575);
FORCEPROP 1 LASTPIN (-6875 3500) $PN 1
J 0
(-6870 3462);
DISPLAY 0.489362 (-6870 3462);
PAINT MONO (-6870 3462);
FORCEPROP 1 LASTPIN (-6875 3300) $PN 2
J 0
(-6870 3310);
DISPLAY 0.489362 (-6870 3310);
PAINT MONO (-6870 3310);
FORCEPROP 1 LAST PACK_TYPE 0402LF
J 0
(-6835 3225);
DISPLAY 0.489362 (-6835 3225);
PAINT SKYBLUE (-6835 3225);
FORCEPROP 1 LAST WATTAGE 1/16W
J 0
(-6835 3375);
DISPLAY 0.489362 (-6835 3375);
PAINT SKYBLUE (-6835 3375);
FORCEPROP 1 LAST MATERIAL CHIP
J 0
(-6835 3325);
DISPLAY 0.489362 (-6835 3325);
PAINT SKYBLUE (-6835 3325);
FORCEPROP 1 LAST TOLERANCE 5%
J 0
(-6830 3425);
DISPLAY 0.489362 (-6830 3425);
PAINT SKYBLUE (-6830 3425);
FORCEPROP 1 LAST VALUE 0
J 0
(-6830 3475);
DISPLAY 0.489362 (-6830 3475);
PAINT SKYBLUE (-6830 3475);
FORCEPROP 2 LAST CDS_LIB pure_quanta
J 0
(-6875 3400);
DISPLAY INVISIBLE (-6875 3400);
FORCEPROP 1 LAST PATH I12
J 0
(-6825 3575);
DISPLAY 0.978723 (-6825 3575);
PAINT WHITE (-6825 3575);
DISPLAY INVISIBLE (-6825 3575);
FORCEPROP 1 LAST PART_NUMBER CS00002JB13
J 0
(-6835 3275);
DISPLAY 0.489362 (-6835 3275);
PAINT SKYBLUE (-6835 3275);
DISPLAY INVISIBLE (-6835 3275);
FORCEADD UNIVERSAL_POWER..1
(-6875 3600);
FORCEPROP 3 LASTPIN (-6875 3550) SIG_NAME P3V3_AUX\g
J 0
(-6865 3560);
DISPLAY 0.659574 (-6865 3560);
PAINT MONO (-6865 3560);
DISPLAY INVISIBLE (-6865 3560);
FORCEPROP 1 LAST HDL_POWER P3V3_AUX
J 1
(-6875 3650);
DISPLAY 0.489362 (-6875 3650);
PAINT GREEN (-6875 3650);
FORCEPROP 2 LAST CDS_LIB mstr_symbols
J 0
(-6875 3600);
PAINT MONO (-6875 3600);
DISPLAY INVISIBLE (-6875 3600);
FORCEPROP 1 LAST PATH I13
J 0
(-6825 3625);
DISPLAY 0.872340 (-6825 3625);
PAINT AQUA (-6825 3625);
DISPLAY INVISIBLE (-6825 3625);
FORCEADD Q_RES..1
(-6850 3800);
FORCEPROP 1 LAST LOCATION PR398
J 0
(-6900 3850);
DISPLAY 0.489362 (-6900 3850);
PAINT SKYBLUE (-6900 3850);
FORCEPROP 0 LAST $SEC 1
J 0
(-6900 3875);
DISPLAY 0.680851 (-6900 3875);
PAINT MONO (-6900 3875);
DISPLAY INVISIBLE (-6900 3875);
FORCEPROP 0 LAST CDS_SEC 1
J 0
(-6900 3875);
DISPLAY 1.021277 (-6900 3875);
DISPLAY INVISIBLE (-6900 3875);
FORCEPROP 1 LASTPIN (-6950 3800) $PN 1
J 0
(-6938 3812);
DISPLAY 0.489362 (-6938 3812);
PAINT MONO (-6938 3812);
FORCEPROP 1 LASTPIN (-6750 3800) $PN 2
J 0
(-6788 3812);
DISPLAY 0.489362 (-6788 3812);
PAINT MONO (-6788 3812);
FORCEPROP 1 LAST MATERIAL CHIP
J 0
(-7150 3700);
DISPLAY 0.489362 (-7150 3700);
PAINT SKYBLUE (-7150 3700);
FORCEPROP 1 LAST WATTAGE 1/16W
J 0
(-6775 3700);
DISPLAY 0.489362 (-6775 3700);
PAINT SKYBLUE (-6775 3700);
FORCEPROP 1 LAST PACK_TYPE 0402LF
J 0
(-6775 3725);
DISPLAY 0.489362 (-6775 3725);
PAINT SKYBLUE (-6775 3725);
FORCEPROP 1 LAST TOLERANCE 5%
J 0
(-6725 3825);
DISPLAY 0.489362 (-6725 3825);
PAINT SKYBLUE (-6725 3825);
FORCEPROP 1 LAST VALUE 0
J 2
(-7025 3825);
DISPLAY 0.489362 (-7025 3825);
PAINT SKYBLUE (-7025 3825);
FORCEPROP 2 LAST CDS_LIB pure_quanta
J 0
(-6850 3800);
DISPLAY INVISIBLE (-6850 3800);
FORCEPROP 1 LAST PATH I14
J 0
(-6900 3950);
DISPLAY 0.978723 (-6900 3950);
PAINT WHITE (-6900 3950);
DISPLAY INVISIBLE (-6900 3950);
FORCEPROP 1 LAST PART_NUMBER CS00002JB13
J 0
(-7150 3725);
DISPLAY 0.489362 (-7150 3725);
PAINT SKYBLUE (-7150 3725);
DISPLAY INVISIBLE (-7150 3725);
FORCEADD MPQ8633BGLEC838Z..1
(-5425 3825);
FORCEPROP 1 LAST LOCATION PU3
J 0
(-5672 4732);
DISPLAY 0.489362 (-5672 4732);
PAINT SKYBLUE (-5672 4732);
FORCEPROP 0 LAST $SEC 1
J 0
(-5675 4900);
DISPLAY 0.680851 (-5675 4900);
PAINT MONO (-5675 4900);
DISPLAY INVISIBLE (-5675 4900);
FORCEPROP 0 LAST CDS_SEC 1
J 0
(-5675 4900);
DISPLAY 1.021277 (-5675 4900);
DISPLAY INVISIBLE (-5675 4900);
FORCEPROP 0 LASTPIN (-5025 3150) $PN 2
J 0
(-5015 3160);
DISPLAY 0.489362 (-5015 3160);
PAINT MONO (-5015 3160);
FORCEPROP 0 LASTPIN (-5025 4300) $PN 1
J 0
(-5015 4310);
DISPLAY 0.489362 (-5015 4310);
PAINT MONO (-5015 4310);
FORCEPROP 0 LASTPIN (-5825 3200) $PN 3
J 2
(-5835 3210);
DISPLAY 0.489362 (-5835 3210);
PAINT MONO (-5835 3210);
FORCEPROP 0 LASTPIN (-5825 4000) $PN 8
J 2
(-5835 4010);
DISPLAY 0.489362 (-5835 4010);
PAINT MONO (-5835 4010);
FORCEPROP 0 LASTPIN (-5025 3550) $PN 7
J 0
(-5015 3560);
DISPLAY 0.489362 (-5015 3560);
PAINT MONO (-5015 3560);
FORCEPROP 0 LASTPIN (-5825 3800) $PN 4
J 2
(-5835 3810);
DISPLAY 0.489362 (-5835 3810);
PAINT MONO (-5835 3810);
FORCEPROP 0 LASTPIN (-5025 3200) $PN 11_18
J 0
(-5015 3210);
DISPLAY 0.489362 (-5015 3210);
PAINT MONO (-5015 3210);
FORCEPROP 0 LASTPIN (-5025 4500) $PN 9
J 0
(-5015 4510);
DISPLAY 0.489362 (-5015 4510);
PAINT MONO (-5015 4510);
FORCEPROP 0 LASTPIN (-5025 3400) $PN 6
J 0
(-5015 3410);
DISPLAY 0.489362 (-5015 3410);
PAINT MONO (-5015 3410);
FORCEPROP 0 LASTPIN (-5025 4000) $PN 20
J 0
(-5015 4010);
DISPLAY 0.489362 (-5015 4010);
PAINT MONO (-5015 4010);
FORCEPROP 0 LASTPIN (-5025 3300) $PN 5
J 0
(-5015 3310);
DISPLAY 0.489362 (-5015 3310);
PAINT MONO (-5015 3310);
FORCEPROP 0 LASTPIN (-5825 3550) $PN 19
J 2
(-5835 3560);
DISPLAY 0.489362 (-5835 3560);
PAINT MONO (-5835 3560);
FORCEPROP 0 LASTPIN (-5825 4500) $PN 10
J 2
(-5835 4510);
DISPLAY 0.489362 (-5835 4510);
PAINT MONO (-5835 4510);
FORCEPROP 0 LASTPIN (-5825 4450) $PN 21
J 2
(-5835 4460);
DISPLAY 0.489362 (-5835 4460);
PAINT MONO (-5835 4460);
FORCEPROP 1 LAST MATERIAL IC
J 0
(-5672 4554);
DISPLAY 0.489362 (-5672 4554);
PAINT SKYBLUE (-5672 4554);
FORCEPROP 2 LAST PART_TYPE SMLF
J 0
(-5675 4850);
DISPLAY 0.680851 (-5675 4850);
FORCEPROP 2 LAST VALUE MPQ8633BGLE-C838-Z
J 0
(-5675 4800);
DISPLAY 0.489362 (-5675 4800);
PAINT SKYBLUE (-5675 4800);
FORCEPROP 1 LAST CDS_LMAN_SYM_OUTLINE -250,725,250,-725
J 0
(-5425 3825);
DISPLAY 0.468085 (-5425 3825);
PAINT GREEN (-5425 3825);
DISPLAY INVISIBLE (-5425 3825);
FORCEPROP 1 LAST NEEDS_NO_SIZE TRUE
J 0
(-5425 3825);
DISPLAY 0.723404 (-5425 3825);
PAINT GREEN (-5425 3825);
DISPLAY INVISIBLE (-5425 3825);
FORCEPROP 2 LAST CDS_LIB pure_quanta
J 0
(-5425 3825);
DISPLAY INVISIBLE (-5425 3825);
FORCEPROP 1 LAST PATH I15
J 0
(-5425 3825);
DISPLAY 0.723404 (-5425 3825);
PAINT GREEN (-5425 3825);
DISPLAY INVISIBLE (-5425 3825);
FORCEPROP 1 LAST PART_NUMBER AL008633005
J 0
(-5672 4633);
DISPLAY 0.489362 (-5672 4633);
PAINT SKYBLUE (-5672 4633);
DISPLAY INVISIBLE (-5672 4633);
FORCEADD UNIVERSAL_GND..1
(-4875 2875);
FORCEPROP 3 LASTPIN (-4875 2925) SIG_NAME GND\g
J 0
(-4865 2935);
DISPLAY 0.659574 (-4865 2935);
PAINT MONO (-4865 2935);
DISPLAY INVISIBLE (-4865 2935);
FORCEPROP 2 LAST CDS_LIB pure_quanta_power
J 0
(-4875 2875);
DISPLAY INVISIBLE (-4875 2875);
FORCEPROP 1 LAST HDL_POWER GND
J 1
(-4850 2800);
DISPLAY 0.872340 (-4850 2800);
PAINT GREEN (-4850 2800);
DISPLAY INVISIBLE (-4850 2800);
FORCEPROP 1 LAST PATH I16
J 0
(-4800 2875);
DISPLAY 0.872340 (-4800 2875);
PAINT AQUA (-4800 2875);
DISPLAY INVISIBLE (-4800 2875);
FORCEADD UNIVERSAL_GND..1
(-4700 2875);
FORCEPROP 3 LASTPIN (-4700 2925) SIG_NAME GND\g
J 0
(-4690 2935);
DISPLAY 0.659574 (-4690 2935);
PAINT MONO (-4690 2935);
DISPLAY INVISIBLE (-4690 2935);
FORCEPROP 2 LAST CDS_LIB pure_quanta_power
J 0
(-4700 2875);
DISPLAY INVISIBLE (-4700 2875);
FORCEPROP 1 LAST HDL_POWER GND
J 1
(-4675 2800);
DISPLAY 0.872340 (-4675 2800);
PAINT GREEN (-4675 2800);
DISPLAY INVISIBLE (-4675 2800);
FORCEPROP 1 LAST PATH I17
J 0
(-4625 2875);
DISPLAY 0.872340 (-4625 2875);
PAINT AQUA (-4625 2875);
DISPLAY INVISIBLE (-4625 2875);
FORCEADD Q_CAP..1
(-4700 3125);
FORCEPROP 1 LAST LOCATION PC153
J 0
(-4650 3175);
DISPLAY 0.489362 (-4650 3175);
PAINT SKYBLUE (-4650 3175);
FORCEPROP 0 LAST $SEC 1
J 0
(-4650 3250);
DISPLAY 0.680851 (-4650 3250);
PAINT MONO (-4650 3250);
DISPLAY INVISIBLE (-4650 3250);
FORCEPROP 2 LAST CDS_SEC 1
J 0
(-4650 3325);
DISPLAY 0.680851 (-4650 3325);
DISPLAY INVISIBLE (-4650 3325);
FORCEPROP 1 LASTPIN (-4700 3225) $PN 1
J 0
(-4690 3205);
DISPLAY 0.489362 (-4690 3205);
PAINT MONO (-4690 3205);
FORCEPROP 1 LASTPIN (-4700 3025) $PN 2
J 0
(-4690 3005);
DISPLAY 0.489362 (-4690 3005);
PAINT MONO (-4690 3005);
FORCEPROP 1 LAST VALUE 0.022UF
J 0
(-4650 3125);
DISPLAY 0.489362 (-4650 3125);
PAINT SKYBLUE (-4650 3125);
FORCEPROP 1 LAST TOLERANCE 10%
J 0
(-4650 3025);
DISPLAY 0.489362 (-4650 3025);
PAINT SKYBLUE (-4650 3025);
FORCEPROP 1 LAST MATERIAL X7R
J 0
(-4650 2975);
DISPLAY 0.489362 (-4650 2975);
PAINT SKYBLUE (-4650 2975);
FORCEPROP 1 LAST VOLTAGE 25V
J 0
(-4650 3075);
DISPLAY 0.489362 (-4650 3075);
PAINT SKYBLUE (-4650 3075);
FORCEPROP 1 LAST PACK_TYPE 0402
J 0
(-4650 2875);
DISPLAY 0.489362 (-4650 2875);
PAINT SKYBLUE (-4650 2875);
FORCEPROP 2 LAST CDS_LIB pure_quanta
J 0
(-4700 3125);
DISPLAY INVISIBLE (-4700 3125);
FORCEPROP 1 LAST PATH I18
J 0
(-4650 3275);
DISPLAY 0.978723 (-4650 3275);
PAINT WHITE (-4650 3275);
DISPLAY INVISIBLE (-4650 3275);
FORCEPROP 1 LAST PART_NUMBER CH3224K1B01
J 0
(-4650 2925);
DISPLAY 0.489362 (-4650 2925);
PAINT SKYBLUE (-4650 2925);
DISPLAY INVISIBLE (-4650 2925);
FORCEADD Q_CAP..1
R 1
(-4275 3300);
FORCEPROP 1 LAST LOCATION PC62
J 0
(-4325 3350);
DISPLAY 0.489362 (-4325 3350);
PAINT SKYBLUE (-4325 3350);
FORCEPROP 0 LAST $SEC 1
R 1
J 0
(-4275 3375);
DISPLAY 0.680851 (-4275 3375);
PAINT MONO (-4275 3375);
DISPLAY INVISIBLE (-4275 3375);
FORCEPROP 0 LAST CDS_SEC 1
R 1
J 0
(-4275 3375);
DISPLAY 1.021277 (-4275 3375);
DISPLAY INVISIBLE (-4275 3375);
FORCEPROP 1 LASTPIN (-4375 3300) $PN 1
J 0
(-4355 3310);
DISPLAY 0.489362 (-4355 3310);
PAINT MONO (-4355 3310);
FORCEPROP 1 LASTPIN (-4175 3300) $PN 2
J 0
(-4235 3310);
DISPLAY 0.489362 (-4235 3310);
PAINT MONO (-4235 3310);
FORCEPROP 1 LAST PACK_TYPE 0402
J 0
(-4200 3200);
DISPLAY 0.489362 (-4200 3200);
PAINT SKYBLUE (-4200 3200);
FORCEPROP 1 LAST MATERIAL X7R
J 0
(-4200 3250);
DISPLAY 0.489362 (-4200 3250);
PAINT SKYBLUE (-4200 3250);
FORCEPROP 1 LAST TOLERANCE 10%
J 0
(-4425 3200);
DISPLAY 0.489362 (-4425 3200);
PAINT SKYBLUE (-4425 3200);
FORCEPROP 1 LAST VALUE 0.1UF
J 0
(-4475 3350);
DISPLAY 0.489362 (-4475 3350);
PAINT SKYBLUE (-4475 3350);
FORCEPROP 1 LAST VOLTAGE 25V
J 0
(-4200 3350);
DISPLAY 0.489362 (-4200 3350);
PAINT SKYBLUE (-4200 3350);
FORCEPROP 2 LAST CDS_LIB pure_quanta
R 1
J 0
(-4275 3300);
DISPLAY INVISIBLE (-4275 3300);
FORCEPROP 1 LAST PATH I19
R 1
J 0
(-4425 3350);
DISPLAY 0.978723 (-4425 3350);
PAINT WHITE (-4425 3350);
DISPLAY INVISIBLE (-4425 3350);
FORCEPROP 1 LAST PART_NUMBER CH4104K1B00
J 0
(-4550 3250);
DISPLAY 0.489362 (-4550 3250);
PAINT SKYBLUE (-4550 3250);
DISPLAY INVISIBLE (-4550 3250);
FORCEADD UNIVERSAL_GND..1
(-8800 4225);
FORCEPROP 3 LASTPIN (-8800 4275) SIG_NAME GND\g
J 0
(-8790 4285);
DISPLAY 0.659574 (-8790 4285);
PAINT MONO (-8790 4285);
DISPLAY INVISIBLE (-8790 4285);
FORCEPROP 2 LAST CDS_LIB pure_quanta_power
J 0
(-8800 4225);
DISPLAY INVISIBLE (-8800 4225);
FORCEPROP 1 LAST HDL_POWER GND
J 1
(-8775 4150);
DISPLAY 0.872340 (-8775 4150);
PAINT GREEN (-8775 4150);
DISPLAY INVISIBLE (-8775 4150);
FORCEPROP 1 LAST PATH I2
J 0
(-8725 4225);
DISPLAY 0.872340 (-8725 4225);
PAINT AQUA (-8725 4225);
DISPLAY INVISIBLE (-8725 4225);
FORCEADD UNIVERSAL_GND..1
(-7750 4175);
FORCEPROP 3 LASTPIN (-7750 4225) SIG_NAME GND\g
J 0
(-7740 4235);
DISPLAY 0.659574 (-7740 4235);
PAINT MONO (-7740 4235);
DISPLAY INVISIBLE (-7740 4235);
FORCEPROP 2 LAST CDS_LIB pure_quanta_power
J 0
(-7750 4175);
DISPLAY INVISIBLE (-7750 4175);
FORCEPROP 1 LAST HDL_POWER GND
J 1
(-7725 4100);
DISPLAY 0.872340 (-7725 4100);
PAINT GREEN (-7725 4100);
DISPLAY INVISIBLE (-7725 4100);
FORCEPROP 1 LAST PATH I20
J 0
(-7675 4175);
DISPLAY 0.872340 (-7675 4175);
PAINT AQUA (-7675 4175);
DISPLAY INVISIBLE (-7675 4175);
FORCEADD Q_CAP..1
(-7150 4550);
FORCEPROP 1 LAST LOCATION PC61
J 0
(-7100 4650);
DISPLAY 0.489362 (-7100 4650);
PAINT SKYBLUE (-7100 4650);
FORCEPROP 0 LAST $SEC 1
J 0
(-7100 4675);
DISPLAY 0.680851 (-7100 4675);
PAINT MONO (-7100 4675);
DISPLAY INVISIBLE (-7100 4675);
FORCEPROP 0 LAST CDS_SEC 1
J 0
(-7100 4700);
DISPLAY 1.021277 (-7100 4700);
DISPLAY INVISIBLE (-7100 4700);
FORCEPROP 1 LASTPIN (-7150 4650) $PN 1
J 0
(-7140 4630);
DISPLAY 0.489362 (-7140 4630);
PAINT MONO (-7140 4630);
FORCEPROP 1 LASTPIN (-7150 4450) $PN 2
J 0
(-7140 4430);
DISPLAY 0.489362 (-7140 4430);
PAINT MONO (-7140 4430);
FORCEPROP 1 LAST VOLTAGE 16V
J 0
(-7100 4550);
DISPLAY 0.489362 (-7100 4550);
PAINT SKYBLUE (-7100 4550);
FORCEPROP 1 LAST VALUE 22UF
J 0
(-7100 4600);
DISPLAY 0.489362 (-7100 4600);
PAINT SKYBLUE (-7100 4600);
FORCEPROP 1 LAST MATERIAL X6S
J 0
(-7100 4450);
DISPLAY 0.489362 (-7100 4450);
PAINT SKYBLUE (-7100 4450);
FORCEPROP 1 LAST PACK_TYPE C0805
J 0
(-7100 4350);
DISPLAY 0.489362 (-7100 4350);
PAINT SKYBLUE (-7100 4350);
FORCEPROP 1 LAST TOLERANCE 20%
J 0
(-7100 4500);
DISPLAY 0.489362 (-7100 4500);
PAINT SKYBLUE (-7100 4500);
FORCEPROP 2 LAST CDS_LIB pure_quanta
J 0
(-7150 4550);
DISPLAY INVISIBLE (-7150 4550);
FORCEPROP 1 LAST PATH I21
J 0
(-7100 4700);
DISPLAY 0.978723 (-7100 4700);
PAINT WHITE (-7100 4700);
DISPLAY INVISIBLE (-7100 4700);
FORCEPROP 1 LAST PART_NUMBER CH6223MEA01
J 0
(-7100 4400);
DISPLAY 0.489362 (-7100 4400);
PAINT SKYBLUE (-7100 4400);
DISPLAY INVISIBLE (-7100 4400);
FORCEADD Q_CAP..1
(-6825 4550);
FORCEPROP 1 LAST LOCATION PC150
J 0
(-6775 4650);
DISPLAY 0.489362 (-6775 4650);
PAINT SKYBLUE (-6775 4650);
FORCEPROP 0 LAST $SEC 1
J 0
(-6775 4675);
DISPLAY 0.680851 (-6775 4675);
PAINT MONO (-6775 4675);
DISPLAY INVISIBLE (-6775 4675);
FORCEPROP 0 LAST CDS_SEC 1
J 0
(-6775 4700);
DISPLAY 1.021277 (-6775 4700);
DISPLAY INVISIBLE (-6775 4700);
FORCEPROP 1 LASTPIN (-6825 4650) $PN 1
J 0
(-6815 4630);
DISPLAY 0.489362 (-6815 4630);
PAINT MONO (-6815 4630);
FORCEPROP 1 LASTPIN (-6825 4450) $PN 2
J 0
(-6815 4430);
DISPLAY 0.489362 (-6815 4430);
PAINT MONO (-6815 4430);
FORCEPROP 1 LAST PACK_TYPE C0805
J 0
(-6775 4350);
DISPLAY 0.489362 (-6775 4350);
PAINT SKYBLUE (-6775 4350);
FORCEPROP 1 LAST MATERIAL X6S
J 0
(-6775 4450);
DISPLAY 0.489362 (-6775 4450);
PAINT SKYBLUE (-6775 4450);
FORCEPROP 1 LAST VALUE 22UF
J 0
(-6775 4600);
DISPLAY 0.489362 (-6775 4600);
PAINT SKYBLUE (-6775 4600);
FORCEPROP 1 LAST VOLTAGE 16V
J 0
(-6775 4550);
DISPLAY 0.489362 (-6775 4550);
PAINT SKYBLUE (-6775 4550);
FORCEPROP 1 LAST TOLERANCE 20%
J 0
(-6775 4500);
DISPLAY 0.489362 (-6775 4500);
PAINT SKYBLUE (-6775 4500);
FORCEPROP 2 LAST CDS_LIB pure_quanta
J 0
(-6825 4550);
DISPLAY INVISIBLE (-6825 4550);
FORCEPROP 1 LAST PATH I22
J 0
(-6775 4700);
DISPLAY 0.978723 (-6775 4700);
PAINT WHITE (-6775 4700);
DISPLAY INVISIBLE (-6775 4700);
FORCEPROP 1 LAST PART_NUMBER CH6223MEA01
J 0
(-6775 4400);
DISPLAY 0.489362 (-6775 4400);
PAINT SKYBLUE (-6775 4400);
DISPLAY INVISIBLE (-6775 4400);
FORCEADD Q_CAP..1
(-6575 4550);
FORCEPROP 1 LAST LOCATION PC152
J 0
(-6525 4650);
DISPLAY 0.489362 (-6525 4650);
PAINT SKYBLUE (-6525 4650);
FORCEPROP 0 LAST $SEC 1
J 0
(-6525 4675);
DISPLAY 0.680851 (-6525 4675);
PAINT MONO (-6525 4675);
DISPLAY INVISIBLE (-6525 4675);
FORCEPROP 0 LAST CDS_SEC 1
J 0
(-6525 4700);
DISPLAY 0.680851 (-6525 4700);
DISPLAY INVISIBLE (-6525 4700);
FORCEPROP 1 LASTPIN (-6575 4650) $PN 1
J 0
(-6565 4630);
DISPLAY 0.489362 (-6565 4630);
PAINT MONO (-6565 4630);
FORCEPROP 1 LASTPIN (-6575 4450) $PN 2
J 0
(-6565 4430);
DISPLAY 0.489362 (-6565 4430);
PAINT MONO (-6565 4430);
FORCEPROP 1 LAST TOLERANCE 20%
J 0
(-6525 4500);
DISPLAY 0.489362 (-6525 4500);
PAINT SKYBLUE (-6525 4500);
FORCEPROP 1 LAST VOLTAGE 16V
J 0
(-6525 4550);
DISPLAY 0.489362 (-6525 4550);
PAINT SKYBLUE (-6525 4550);
FORCEPROP 1 LAST VALUE 22UF
J 0
(-6525 4600);
DISPLAY 0.489362 (-6525 4600);
PAINT SKYBLUE (-6525 4600);
FORCEPROP 1 LAST MATERIAL X6S
J 0
(-6525 4450);
DISPLAY 0.489362 (-6525 4450);
PAINT SKYBLUE (-6525 4450);
FORCEPROP 1 LAST PACK_TYPE C0805
J 0
(-6525 4350);
DISPLAY 0.489362 (-6525 4350);
PAINT SKYBLUE (-6525 4350);
FORCEPROP 2 LAST CDS_LIB pure_quanta
J 0
(-6575 4550);
DISPLAY INVISIBLE (-6575 4550);
FORCEPROP 1 LAST PATH I23
J 0
(-6525 4700);
DISPLAY 0.978723 (-6525 4700);
PAINT WHITE (-6525 4700);
DISPLAY INVISIBLE (-6525 4700);
FORCEPROP 1 LAST PART_NUMBER CH6223MEA01
J 0
(-6525 4400);
DISPLAY 0.489362 (-6525 4400);
PAINT SKYBLUE (-6525 4400);
DISPLAY INVISIBLE (-6525 4400);
FORCEADD Q_CAP..1
(-6325 4550);
FORCEPROP 1 LAST LOCATION PC22
J 0
(-6275 4650);
DISPLAY 0.489362 (-6275 4650);
PAINT SKYBLUE (-6275 4650);
FORCEPROP 0 LAST $SEC 1
J 0
(-6275 4675);
DISPLAY 0.680851 (-6275 4675);
PAINT MONO (-6275 4675);
DISPLAY INVISIBLE (-6275 4675);
FORCEPROP 0 LAST CDS_SEC 1
J 0
(-6275 4675);
DISPLAY 1.021277 (-6275 4675);
DISPLAY INVISIBLE (-6275 4675);
FORCEPROP 1 LASTPIN (-6325 4650) $PN 1
J 0
(-6315 4630);
DISPLAY 0.489362 (-6315 4630);
PAINT MONO (-6315 4630);
FORCEPROP 1 LASTPIN (-6325 4450) $PN 2
J 0
(-6315 4430);
DISPLAY 0.489362 (-6315 4430);
PAINT MONO (-6315 4430);
FORCEPROP 1 LAST VOLTAGE 25V
J 0
(-6275 4550);
DISPLAY 0.489362 (-6275 4550);
PAINT SKYBLUE (-6275 4550);
FORCEPROP 1 LAST TOLERANCE 10%
J 0
(-6275 4500);
DISPLAY 0.489362 (-6275 4500);
PAINT SKYBLUE (-6275 4500);
FORCEPROP 1 LAST MATERIAL X6S
J 0
(-6275 4450);
DISPLAY 0.489362 (-6275 4450);
PAINT SKYBLUE (-6275 4450);
FORCEPROP 1 LAST VALUE 1UF
J 0
(-6275 4600);
DISPLAY 0.489362 (-6275 4600);
PAINT SKYBLUE (-6275 4600);
FORCEPROP 1 LAST PACK_TYPE C0402
J 0
(-6275 4350);
DISPLAY 0.489362 (-6275 4350);
PAINT SKYBLUE (-6275 4350);
FORCEPROP 2 LAST CDS_LIB pure_quanta
J 0
(-6325 4550);
PAINT MONO (-6325 4550);
DISPLAY INVISIBLE (-6325 4550);
FORCEPROP 1 LAST PATH I24
J 0
(-6275 4700);
DISPLAY 0.978723 (-6275 4700);
PAINT WHITE (-6275 4700);
DISPLAY INVISIBLE (-6275 4700);
FORCEPROP 1 LAST PART_NUMBER CH5104KEB02
J 0
(-6275 4400);
DISPLAY 0.489362 (-6275 4400);
PAINT SKYBLUE (-6275 4400);
DISPLAY INVISIBLE (-6275 4400);
FORCEADD Q_CAP..1
(-3775 4125);
FORCEPROP 1 LAST LOCATION PC19
J 0
(-3725 4300);
DISPLAY 0.489362 (-3725 4300);
PAINT SKYBLUE (-3725 4300);
FORCEPROP 2 LAST SEC 1
J 0
(-3701 4344);
DISPLAY 0.680851 (-3701 4344);
PAINT MONO (-3701 4344);
DISPLAY INVISIBLE (-3701 4344);
FORCEPROP 1 LASTPIN (-3775 4225) $PN 1
J 0
(-3765 4205);
DISPLAY 0.489362 (-3765 4205);
FORCEPROP 1 LASTPIN (-3775 4025) $PN 2
J 0
(-3765 4005);
DISPLAY 0.489362 (-3765 4005);
FORCEPROP 1 LAST TOLERANCE 10%
J 0
(-3725 4150);
DISPLAY 0.489362 (-3725 4150);
PAINT SKYBLUE (-3725 4150);
FORCEPROP 1 LAST VALUE 0.22UF
J 0
(-3725 4250);
DISPLAY 0.489362 (-3725 4250);
PAINT SKYBLUE (-3725 4250);
FORCEPROP 1 LAST PACK_TYPE 0402
J 0
(-3725 4000);
DISPLAY 0.489362 (-3725 4000);
PAINT SKYBLUE (-3725 4000);
FORCEPROP 1 LAST MATERIAL X7R
J 0
(-3725 4100);
DISPLAY 0.489362 (-3725 4100);
PAINT SKYBLUE (-3725 4100);
FORCEPROP 1 LAST VOLTAGE 16V
J 0
(-3725 4200);
DISPLAY 0.489362 (-3725 4200);
PAINT SKYBLUE (-3725 4200);
FORCEPROP 2 LAST CDS_LIB pure_quanta
J 0
(-3775 4125);
PAINT MONO (-3775 4125);
DISPLAY INVISIBLE (-3775 4125);
FORCEPROP 2 LAST SEC_TYPE 0402
J 0
(-3701 4344);
DISPLAY 1.021277 (-3701 4344);
DISPLAY INVISIBLE (-3701 4344);
FORCEPROP 1 LAST PATH I25
J 0
(-3725 4275);
DISPLAY 0.978723 (-3725 4275);
PAINT WHITE (-3725 4275);
DISPLAY INVISIBLE (-3725 4275);
FORCEPROP 1 LAST PART_NUMBER CH4223K1B00
J 0
(-3725 4050);
DISPLAY 0.489362 (-3725 4050);
PAINT SKYBLUE (-3725 4050);
DISPLAY INVISIBLE (-3725 4050);
FORCEADD Q_RES..2
(-4375 4800);
FORCEPROP 1 LAST LOCATION R8009
J 0
(-4330 4925);
DISPLAY 0.489362 (-4330 4925);
PAINT SKYBLUE (-4330 4925);
FORCEPROP 2 LAST SEC 1
J 0
(-4324 5029);
DISPLAY 0.680851 (-4324 5029);
PAINT MONO (-4324 5029);
DISPLAY INVISIBLE (-4324 5029);
FORCEPROP 1 LASTPIN (-4375 4900) $PN 1
J 0
(-4370 4862);
DISPLAY 0.489362 (-4370 4862);
FORCEPROP 1 LASTPIN (-4375 4700) $PN 2
J 0
(-4370 4710);
DISPLAY 0.489362 (-4370 4710);
FORCEPROP 1 LAST PACK_TYPE 0402LF
J 0
(-4335 4625);
DISPLAY 0.489362 (-4335 4625);
PAINT SKYBLUE (-4335 4625);
FORCEPROP 1 LAST WATTAGE 1/16W
J 0
(-4335 4775);
DISPLAY 0.489362 (-4335 4775);
PAINT SKYBLUE (-4335 4775);
FORCEPROP 1 LAST MATERIAL CHIP
J 0
(-4335 4725);
DISPLAY 0.489362 (-4335 4725);
PAINT SKYBLUE (-4335 4725);
FORCEPROP 1 LAST VALUE 10K
J 0
(-4330 4875);
DISPLAY 0.489362 (-4330 4875);
PAINT SKYBLUE (-4330 4875);
FORCEPROP 1 LAST TOLERANCE 5%
J 0
(-4330 4825);
DISPLAY 0.489362 (-4330 4825);
PAINT SKYBLUE (-4330 4825);
FORCEPROP 2 LAST CDS_LIB pure_quanta
R 3
J 0
(-4375 4800);
PAINT MONO (-4375 4800);
DISPLAY INVISIBLE (-4375 4800);
FORCEPROP 2 LAST SEC_TYPE 0402LF
J 0
(-4324 5029);
DISPLAY 1.021277 (-4324 5029);
DISPLAY INVISIBLE (-4324 5029);
FORCEPROP 1 LAST PATH I26
J 0
(-4325 4975);
DISPLAY 0.978723 (-4325 4975);
PAINT WHITE (-4325 4975);
DISPLAY INVISIBLE (-4325 4975);
FORCEPROP 1 LAST PART_NUMBER CS31002JB08
J 0
(-4335 4675);
DISPLAY 0.489362 (-4335 4675);
PAINT SKYBLUE (-4335 4675);
DISPLAY INVISIBLE (-4335 4675);
FORCEADD UNIVERSAL_POWER..1
(-4375 5075);
FORCEPROP 3 LASTPIN (-4375 5025) SIG_NAME P3V3_AUX\g
J 0
(-4365 5035);
DISPLAY 0.659574 (-4365 5035);
PAINT MONO (-4365 5035);
DISPLAY INVISIBLE (-4365 5035);
FORCEPROP 1 LAST HDL_POWER P3V3_AUX
J 1
(-4375 5125);
DISPLAY 0.489362 (-4375 5125);
PAINT GREEN (-4375 5125);
FORCEPROP 2 LAST CDS_LIB mstr_symbols
J 0
(-4375 5075);
DISPLAY INVISIBLE (-4375 5075);
FORCEPROP 1 LAST PATH I27
J 0
(-4325 5100);
DISPLAY 0.872340 (-4325 5100);
PAINT AQUA (-4325 5100);
DISPLAY INVISIBLE (-4325 5100);
FORCEADD UNIVERSAL_GND..1
(-3300 2125);
FORCEPROP 3 LASTPIN (-3300 2175) SIG_NAME GND\g
J 0
(-3290 2185);
DISPLAY 0.659574 (-3290 2185);
PAINT MONO (-3290 2185);
DISPLAY INVISIBLE (-3290 2185);
FORCEPROP 2 LAST CDS_LIB pure_quanta_power
J 0
(-3300 2125);
DISPLAY INVISIBLE (-3300 2125);
FORCEPROP 1 LAST HDL_POWER GND
J 1
(-3275 2050);
DISPLAY 0.872340 (-3275 2050);
PAINT GREEN (-3275 2050);
DISPLAY INVISIBLE (-3275 2050);
FORCEPROP 1 LAST PATH I28
J 0
(-3225 2125);
DISPLAY 0.872340 (-3225 2125);
PAINT AQUA (-3225 2125);
DISPLAY INVISIBLE (-3225 2125);
FORCEADD Q_RES..1
R 1
(-3300 2350);
FORCEPROP 1 LAST LOCATION PR399
J 0
(-3250 2450);
DISPLAY 0.489362 (-3250 2450);
PAINT SKYBLUE (-3250 2450);
FORCEPROP 0 LAST $SEC 1
R 1
J 0
(-3250 2500);
DISPLAY 0.680851 (-3250 2500);
PAINT MONO (-3250 2500);
DISPLAY INVISIBLE (-3250 2500);
FORCEPROP 0 LAST CDS_SEC 1
R 1
J 0
(-3250 2500);
DISPLAY 1.021277 (-3250 2500);
DISPLAY INVISIBLE (-3250 2500);
FORCEPROP 1 LASTPIN (-3300 2250) $PN 1
J 0
(-3335 2285);
DISPLAY 0.489362 (-3335 2285);
PAINT MONO (-3335 2285);
FORCEPROP 1 LASTPIN (-3300 2450) $PN 2
J 0
(-3335 2410);
DISPLAY 0.489362 (-3335 2410);
PAINT MONO (-3335 2410);
FORCEPROP 1 LAST TOLERANCE 1%
J 0
(-3250 2350);
DISPLAY 0.489362 (-3250 2350);
PAINT SKYBLUE (-3250 2350);
FORCEPROP 1 LAST MATERIAL CHIP
J 0
(-3250 2250);
DISPLAY 0.489362 (-3250 2250);
PAINT SKYBLUE (-3250 2250);
FORCEPROP 1 LAST VALUE 49.9
J 0
(-3250 2400);
DISPLAY 0.489362 (-3250 2400);
PAINT SKYBLUE (-3250 2400);
FORCEPROP 1 LAST WATTAGE 1/16W
J 0
(-3250 2300);
DISPLAY 0.489362 (-3250 2300);
PAINT SKYBLUE (-3250 2300);
FORCEPROP 1 LAST PACK_TYPE 0402LF
J 0
(-3250 2150);
DISPLAY 0.489362 (-3250 2150);
PAINT SKYBLUE (-3250 2150);
FORCEPROP 2 LAST CDS_LIB pure_quanta
R 1
J 0
(-3300 2350);
DISPLAY INVISIBLE (-3300 2350);
FORCEPROP 1 LAST PATH I29
R 1
J 0
(-3450 2300);
DISPLAY 0.978723 (-3450 2300);
PAINT WHITE (-3450 2300);
DISPLAY INVISIBLE (-3450 2300);
FORCEPROP 1 LAST PART_NUMBER CS04992FB07
J 0
(-3250 2200);
DISPLAY 0.489362 (-3250 2200);
PAINT SKYBLUE (-3250 2200);
DISPLAY INVISIBLE (-3250 2200);
FORCEADD Q_CAP..1
(-8800 4575);
FORCEPROP 1 LAST LOCATION PC6002
J 0
(-8750 4675);
DISPLAY 0.489362 (-8750 4675);
PAINT SKYBLUE (-8750 4675);
FORCEPROP 0 LAST $SEC 1
J 0
(-8750 4700);
DISPLAY 0.680851 (-8750 4700);
PAINT MONO (-8750 4700);
DISPLAY INVISIBLE (-8750 4700);
FORCEPROP 0 LAST CDS_SEC 1
J 0
(-8750 4700);
DISPLAY 0.680851 (-8750 4700);
DISPLAY INVISIBLE (-8750 4700);
FORCEPROP 1 LASTPIN (-8800 4675) $PN 1
J 0
(-8790 4655);
DISPLAY 0.787234 (-8790 4655);
PAINT MONO (-8790 4655);
FORCEPROP 1 LASTPIN (-8800 4475) $PN 2
J 0
(-8790 4455);
DISPLAY 0.787234 (-8790 4455);
PAINT MONO (-8790 4455);
FORCEPROP 1 LAST TOLERANCE 10%
J 0
(-8750 4525);
DISPLAY 0.489362 (-8750 4525);
PAINT SKYBLUE (-8750 4525);
FORCEPROP 1 LAST VOLTAGE 25V
J 0
(-8750 4575);
DISPLAY 0.489362 (-8750 4575);
PAINT SKYBLUE (-8750 4575);
FORCEPROP 1 LAST VALUE 0.1UF
J 0
(-8750 4625);
DISPLAY 0.489362 (-8750 4625);
PAINT SKYBLUE (-8750 4625);
FORCEPROP 1 LAST PACK_TYPE 0402
J 0
(-8750 4375);
DISPLAY 0.489362 (-8750 4375);
PAINT SKYBLUE (-8750 4375);
FORCEPROP 1 LAST MATERIAL X7R
J 0
(-8750 4475);
DISPLAY 0.489362 (-8750 4475);
PAINT SKYBLUE (-8750 4475);
FORCEPROP 2 LAST SIGNAL_MODEL DEFAULT_CAPACITOR_100000PF_2_1
J 0
(-8732 4845);
DISPLAY 1.021277 (-8732 4845);
DISPLAY INVISIBLE (-8732 4845);
FORCEPROP 2 LAST CDS_LIB pure_quanta
J 0
(-8800 4575);
DISPLAY INVISIBLE (-8800 4575);
FORCEPROP 1 LAST PATH I3
J 0
(-8750 4725);
DISPLAY 0.978723 (-8750 4725);
PAINT WHITE (-8750 4725);
DISPLAY INVISIBLE (-8750 4725);
FORCEPROP 1 LAST PART_NUMBER CH4104K1B00
J 0
(-8750 4425);
DISPLAY 0.489362 (-8750 4425);
PAINT SKYBLUE (-8750 4425);
DISPLAY INVISIBLE (-8750 4425);
FORCEADD Q_RES..2
(-3875 3250);
FORCEPROP 1 LAST LOCATION PR147
J 0
(-3825 3325);
DISPLAY 0.489362 (-3825 3325);
PAINT SKYBLUE (-3825 3325);
FORCEPROP 2 LAST $SEC 1
J 0
(-3825 3475);
DISPLAY 0.680851 (-3825 3475);
PAINT MONO (-3825 3475);
DISPLAY INVISIBLE (-3825 3475);
FORCEPROP 2 LAST CDS_SEC 1
J 0
(-3825 3475);
DISPLAY 0.680851 (-3825 3475);
DISPLAY INVISIBLE (-3825 3475);
FORCEPROP 1 LASTPIN (-3875 3350) $PN 1
J 0
(-3870 3312);
DISPLAY 0.489362 (-3870 3312);
FORCEPROP 1 LASTPIN (-3875 3150) $PN 2
J 0
(-3870 3160);
DISPLAY 0.489362 (-3870 3160);
FORCEPROP 1 LAST MATERIAL CHIP
J 0
(-3825 3125);
DISPLAY 0.489362 (-3825 3125);
PAINT SKYBLUE (-3825 3125);
FORCEPROP 1 LAST TOLERANCE 1%
J 0
(-3825 3225);
DISPLAY 0.489362 (-3825 3225);
PAINT SKYBLUE (-3825 3225);
FORCEPROP 1 LAST PACK_TYPE 0402LF
J 0
(-3825 3025);
DISPLAY 0.489362 (-3825 3025);
PAINT SKYBLUE (-3825 3025);
FORCEPROP 1 LAST WATTAGE 1/16W
J 0
(-3825 3175);
DISPLAY 0.489362 (-3825 3175);
PAINT SKYBLUE (-3825 3175);
FORCEPROP 1 LAST VALUE 10K
J 0
(-3825 3275);
DISPLAY 0.489362 (-3825 3275);
PAINT SKYBLUE (-3825 3275);
FORCEPROP 2 LAST CDS_LIB pure_quanta
J 0
(-3875 3250);
DISPLAY INVISIBLE (-3875 3250);
FORCEPROP 1 LAST PATH I30
J 0
(-3825 3425);
DISPLAY 0.978723 (-3825 3425);
PAINT WHITE (-3825 3425);
DISPLAY INVISIBLE (-3825 3425);
FORCEPROP 1 LAST PART_NUMBER CS31002FB08
J 0
(-3825 3075);
DISPLAY 0.489362 (-3825 3075);
PAINT SKYBLUE (-3825 3075);
DISPLAY INVISIBLE (-3825 3075);
FORCEADD Q_CAP..2
(-3275 3275);
FORCEPROP 1 LAST LOCATION PC64
J 1
(-3275 3375);
DISPLAY 0.489362 (-3275 3375);
PAINT SKYBLUE (-3275 3375);
FORCEPROP 0 LAST $SEC 1
J 0
(-3275 3425);
DISPLAY 0.680851 (-3275 3425);
PAINT MONO (-3275 3425);
DISPLAY INVISIBLE (-3275 3425);
FORCEPROP 0 LAST CDS_SEC 1
J 0
(-3275 3425);
DISPLAY 0.680851 (-3275 3425);
DISPLAY INVISIBLE (-3275 3425);
FORCEPROP 1 LASTPIN (-3375 3275) $PN 1
J 0
(-3385 3290);
DISPLAY 0.489362 (-3385 3290);
PAINT MONO (-3385 3290);
FORCEPROP 1 LASTPIN (-3175 3275) $PN 2
J 0
(-3190 3290);
DISPLAY 0.489362 (-3190 3290);
PAINT MONO (-3190 3290);
FORCEPROP 1 LAST VALUE 220PF
J 2
(-3375 3325);
DISPLAY 0.489362 (-3375 3325);
PAINT SKYBLUE (-3375 3325);
FORCEPROP 1 LAST TOLERANCE 10%
J 2
(-3425 3175);
DISPLAY 0.489362 (-3425 3175);
PAINT SKYBLUE (-3425 3175);
FORCEPROP 1 LAST PACK_TYPE 0402
J 1
(-3175 3200);
DISPLAY 0.489362 (-3175 3200);
PAINT SKYBLUE (-3175 3200);
FORCEPROP 1 LAST MATERIAL X7R
J 0
(-3200 3225);
DISPLAY 0.489362 (-3200 3225);
PAINT SKYBLUE (-3200 3225);
FORCEPROP 1 LAST VOLTAGE 50V
J 0
(-3200 3325);
DISPLAY 0.489362 (-3200 3325);
PAINT SKYBLUE (-3200 3325);
FORCEPROP 2 LAST CDS_LIB pure_quanta
J 0
(-3275 3275);
DISPLAY INVISIBLE (-3275 3275);
FORCEPROP 1 LAST PATH I31
J 0
(-3275 3475);
DISPLAY 0.978723 (-3275 3475);
PAINT WHITE (-3275 3475);
DISPLAY INVISIBLE (-3275 3475);
FORCEPROP 1 LAST PART_NUMBER TMP_QCH12206KB14
J 1
(-3475 3225);
DISPLAY 0.489362 (-3475 3225);
PAINT SKYBLUE (-3475 3225);
DISPLAY INVISIBLE (-3475 3225);
FORCEADD Q_RES..1
(-3275 3550);
FORCEPROP 1 LAST LOCATION PR148
J 0
(-3325 3600);
DISPLAY 0.489362 (-3325 3600);
PAINT SKYBLUE (-3325 3600);
FORCEPROP 2 LAST $SEC 1
J 0
(-3302 3763);
DISPLAY 0.680851 (-3302 3763);
PAINT MONO (-3302 3763);
DISPLAY INVISIBLE (-3302 3763);
FORCEPROP 2 LAST CDS_SEC 1
J 0
(-3302 3763);
DISPLAY 0.680851 (-3302 3763);
DISPLAY INVISIBLE (-3302 3763);
FORCEPROP 1 LASTPIN (-3375 3550) $PN 1
J 0
(-3363 3562);
DISPLAY 0.489362 (-3363 3562);
FORCEPROP 1 LASTPIN (-3175 3550) $PN 2
J 0
(-3213 3562);
DISPLAY 0.489362 (-3213 3562);
FORCEPROP 1 LAST VALUE 20K
J 2
(-3400 3600);
DISPLAY 0.489362 (-3400 3600);
PAINT SKYBLUE (-3400 3600);
FORCEPROP 1 LAST MATERIAL CHIP
J 0
(-3100 3600);
DISPLAY 0.489362 (-3100 3600);
PAINT SKYBLUE (-3100 3600);
FORCEPROP 1 LAST PACK_TYPE 0402LF
J 0
(-3100 3500);
DISPLAY 0.489362 (-3100 3500);
PAINT SKYBLUE (-3100 3500);
FORCEPROP 2 LAST CDS_LIB pure_quanta
J 0
(-3275 3550);
DISPLAY INVISIBLE (-3275 3550);
FORCEPROP 1 LAST WATTAGE 1/16W
J 2
(-2701 3568);
DISPLAY 0.978723 (-2701 3568);
PAINT SKYBLUE (-2701 3568);
DISPLAY INVISIBLE (-2701 3568);
FORCEPROP 1 LAST TOLERANCE 1%
J 0
(-3155 3569);
DISPLAY 0.978723 (-3155 3569);
PAINT SKYBLUE (-3155 3569);
DISPLAY INVISIBLE (-3155 3569);
FORCEPROP 1 LAST PATH I32
J 0
(-3325 3700);
DISPLAY 0.978723 (-3325 3700);
PAINT WHITE (-3325 3700);
DISPLAY INVISIBLE (-3325 3700);
FORCEPROP 1 LAST PART_NUMBER CS32002FB06
J 0
(-3525 3500);
DISPLAY 0.489362 (-3525 3500);
PAINT SKYBLUE (-3525 3500);
DISPLAY INVISIBLE (-3525 3500);
FORCEADD Q_INDUCTOR..1
(-3275 4025);
FORCEPROP 1 LAST LOCATION PL57
J 0
(-3400 4185);
DISPLAY 0.574468 (-3400 4185);
PAINT SKYBLUE (-3400 4185);
FORCEPROP 0 LAST $SEC 1
J 0
(-3400 4300);
DISPLAY 0.680851 (-3400 4300);
PAINT MONO (-3400 4300);
DISPLAY INVISIBLE (-3400 4300);
FORCEPROP 2 LAST CDS_SEC 1
J 0
(-3400 4325);
DISPLAY 0.680851 (-3400 4325);
DISPLAY INVISIBLE (-3400 4325);
FORCEPROP 0 LASTPIN (-3375 4000) $PN 1
J 2
(-3385 4010);
DISPLAY 0.680851 (-3385 4010);
PAINT MONO (-3385 4010);
FORCEPROP 0 LASTPIN (-3175 4000) $PN 2
J 0
(-3165 4010);
DISPLAY 0.680851 (-3165 4010);
PAINT MONO (-3165 4010);
FORCEPROP 2 LAST VALUE 1.0UH/18A
J 0
(-3400 4225);
DISPLAY 0.489362 (-3400 4225);
PAINT SKYBLUE (-3400 4225);
FORCEPROP 2 LAST PACK_TYPE SMLF
J 0
(-3400 4275);
DISPLAY 0.489362 (-3400 4275);
PAINT SKYBLUE (-3400 4275);
FORCEPROP 1 LAST MATERIAL IND
J 0
(-3400 4080);
DISPLAY 0.574468 (-3400 4080);
PAINT SKYBLUE (-3400 4080);
FORCEPROP 2 LAST CDS_LIB pure_quanta
J 0
(-3275 4025);
DISPLAY INVISIBLE (-3275 4025);
FORCEPROP 1 LAST NEEDS_NO_SIZE TRUE
J 0
(-3275 4025);
DISPLAY 0.468085 (-3275 4025);
PAINT GREEN (-3275 4025);
DISPLAY INVISIBLE (-3275 4025);
FORCEPROP 1 LAST PATH I33
J 0
(-3200 4080);
DISPLAY 0.723404 (-3200 4080);
PAINT GREEN (-3200 4080);
DISPLAY INVISIBLE (-3200 4080);
FORCEPROP 1 LAST PART_NUMBER CV-10I0MZ01
J 0
(-3400 4135);
DISPLAY 0.489362 (-3400 4135);
PAINT SKYBLUE (-3400 4135);
DISPLAY INVISIBLE (-3400 4135);
FORCEADD Q_CAP..1
(-2750 2625);
FORCEPROP 1 LAST LOCATION PC6006
J 0
(-2700 2725);
DISPLAY 0.489362 (-2700 2725);
PAINT SKYBLUE (-2700 2725);
FORCEPROP 0 LAST $SEC 1
J 0
(-2700 2750);
DISPLAY 0.680851 (-2700 2750);
PAINT MONO (-2700 2750);
DISPLAY INVISIBLE (-2700 2750);
FORCEPROP 0 LAST CDS_SEC 1
J 0
(-2700 2750);
DISPLAY 0.680851 (-2700 2750);
DISPLAY INVISIBLE (-2700 2750);
FORCEPROP 1 LASTPIN (-2750 2725) $PN 1
J 0
(-2740 2705);
DISPLAY 0.787234 (-2740 2705);
PAINT MONO (-2740 2705);
FORCEPROP 1 LASTPIN (-2750 2525) $PN 2
J 0
(-2740 2505);
DISPLAY 0.787234 (-2740 2505);
PAINT MONO (-2740 2505);
FORCEPROP 1 LAST VOLTAGE 25V
J 0
(-2700 2625);
DISPLAY 0.489362 (-2700 2625);
PAINT SKYBLUE (-2700 2625);
FORCEPROP 1 LAST TOLERANCE 10%
J 0
(-2700 2575);
DISPLAY 0.489362 (-2700 2575);
PAINT SKYBLUE (-2700 2575);
FORCEPROP 1 LAST PACK_TYPE C0402
J 0
(-2925 2575);
DISPLAY 0.489362 (-2925 2575);
PAINT SKYBLUE (-2925 2575);
FORCEPROP 1 LAST VALUE 0.01UF
J 0
(-2700 2675);
DISPLAY 0.489362 (-2700 2675);
PAINT SKYBLUE (-2700 2675);
FORCEPROP 1 LAST MATERIAL EMPTY
J 0
(-2875 2675);
DISPLAY 0.489362 (-2875 2675);
PAINT SKYBLUE (-2875 2675);
FORCEPROP 2 LAST CDS_LIB pure_quanta
J 0
(-2750 2625);
DISPLAY INVISIBLE (-2750 2625);
FORCEPROP 1 LAST PATH I34
J 0
(-2700 2775);
DISPLAY 0.978723 (-2700 2775);
PAINT WHITE (-2700 2775);
DISPLAY INVISIBLE (-2700 2775);
FORCEPROP 1 LAST PART_NUMBER CH3104K1B11
J 0
(-3050 2625);
DISPLAY 0.489362 (-3050 2625);
PAINT SKYBLUE (-3050 2625);
DISPLAY INVISIBLE (-3050 2625);
FORCEADD Q_RES..2
R 1
(-2150 2500);
FORCEPROP 1 LAST LOCATION PR401
J 0
(-2150 2550);
DISPLAY 0.489362 (-2150 2550);
PAINT SKYBLUE (-2150 2550);
FORCEPROP 0 LAST $SEC 1
R 1
J 0
(-2025 2575);
DISPLAY 0.680851 (-2025 2575);
PAINT MONO (-2025 2575);
DISPLAY INVISIBLE (-2025 2575);
FORCEPROP 0 LAST CDS_SEC 1
R 1
J 0
(-2025 2575);
DISPLAY 1.021277 (-2025 2575);
DISPLAY INVISIBLE (-2025 2575);
FORCEPROP 1 LASTPIN (-2250 2500) $PN 1
J 0
(-2235 2510);
DISPLAY 0.489362 (-2235 2510);
PAINT MONO (-2235 2510);
FORCEPROP 1 LASTPIN (-2050 2500) $PN 2
J 0
(-2085 2510);
DISPLAY 0.489362 (-2085 2510);
PAINT MONO (-2085 2510);
FORCEPROP 1 LAST TOLERANCE 5%
J 0
(-2325 2400);
DISPLAY 0.489362 (-2325 2400);
PAINT SKYBLUE (-2325 2400);
FORCEPROP 1 LAST MATERIAL CHIP
J 0
(-2025 2400);
DISPLAY 0.489362 (-2025 2400);
PAINT SKYBLUE (-2025 2400);
FORCEPROP 1 LAST PACK_TYPE 0402LF
J 0
(-2050 2450);
DISPLAY 0.489362 (-2050 2450);
PAINT SKYBLUE (-2050 2450);
FORCEPROP 1 LAST VALUE 0
R 2
J 0
(-2325 2550);
DISPLAY 0.489362 (-2325 2550);
PAINT SKYBLUE (-2325 2550);
FORCEPROP 1 LAST WATTAGE 1/16W
J 0
(-2025 2525);
DISPLAY 0.489362 (-2025 2525);
PAINT SKYBLUE (-2025 2525);
FORCEPROP 2 LAST CDS_LIB pure_quanta
R 1
J 0
(-2150 2500);
DISPLAY INVISIBLE (-2150 2500);
FORCEPROP 1 LAST PATH I35
R 1
J 0
(-2325 2550);
DISPLAY 0.978723 (-2325 2550);
PAINT WHITE (-2325 2550);
DISPLAY INVISIBLE (-2325 2550);
FORCEPROP 1 LAST PART_NUMBER CS00002JB13
J 0
(-2450 2450);
DISPLAY 0.489362 (-2450 2450);
PAINT SKYBLUE (-2450 2450);
DISPLAY INVISIBLE (-2450 2450);
FORCEADD Q_RES..1
(-2150 2750);
FORCEPROP 1 LAST LOCATION PR400
J 0
(-2175 2800);
DISPLAY 0.489362 (-2175 2800);
PAINT SKYBLUE (-2175 2800);
FORCEPROP 0 LAST $SEC 1
J 0
(-2150 2825);
DISPLAY 0.680851 (-2150 2825);
PAINT MONO (-2150 2825);
DISPLAY INVISIBLE (-2150 2825);
FORCEPROP 0 LAST CDS_SEC 1
J 0
(-2150 2825);
DISPLAY 1.021277 (-2150 2825);
DISPLAY INVISIBLE (-2150 2825);
FORCEPROP 1 LASTPIN (-2250 2750) $PN 1
J 0
(-2238 2762);
DISPLAY 0.489362 (-2238 2762);
PAINT MONO (-2238 2762);
FORCEPROP 1 LASTPIN (-2050 2750) $PN 2
J 0
(-2088 2762);
DISPLAY 0.489362 (-2088 2762);
PAINT MONO (-2088 2762);
FORCEPROP 1 LAST WATTAGE 1/16W
J 2
(-1850 2775);
DISPLAY 0.489362 (-1850 2775);
PAINT SKYBLUE (-1850 2775);
FORCEPROP 1 LAST MATERIAL CHIP
J 0
(-1950 2650);
DISPLAY 0.489362 (-1950 2650);
PAINT SKYBLUE (-1950 2650);
FORCEPROP 1 LAST PACK_TYPE 0402LF
J 0
(-1975 2700);
DISPLAY 0.489362 (-1975 2700);
PAINT SKYBLUE (-1975 2700);
FORCEPROP 1 LAST VALUE 10
J 2
(-2300 2775);
DISPLAY 0.489362 (-2300 2775);
PAINT SKYBLUE (-2300 2775);
FORCEPROP 1 LAST TOLERANCE 1%
J 0
(-2325 2650);
DISPLAY 0.489362 (-2325 2650);
PAINT SKYBLUE (-2325 2650);
FORCEPROP 2 LAST CDS_LIB pure_quanta
J 0
(-2150 2750);
DISPLAY INVISIBLE (-2150 2750);
FORCEPROP 1 LAST PATH I36
J 0
(-2200 2900);
DISPLAY 0.978723 (-2200 2900);
PAINT WHITE (-2200 2900);
DISPLAY INVISIBLE (-2200 2900);
FORCEPROP 1 LAST PART_NUMBER CS01002FB07
J 0
(-2450 2700);
DISPLAY 0.489362 (-2450 2700);
PAINT SKYBLUE (-2450 2700);
DISPLAY INVISIBLE (-2450 2700);
FORCEADD Q_CAP..1
(-2450 3750);
FORCEPROP 1 LAST LOCATION PC65
J 0
(-2400 3850);
DISPLAY 0.489362 (-2400 3850);
PAINT SKYBLUE (-2400 3850);
FORCEPROP 0 LAST $SEC 1
J 0
(-2400 3875);
DISPLAY 0.680851 (-2400 3875);
PAINT MONO (-2400 3875);
DISPLAY INVISIBLE (-2400 3875);
FORCEPROP 0 LAST CDS_SEC 1
J 0
(-2400 3875);
DISPLAY 1.021277 (-2400 3875);
DISPLAY INVISIBLE (-2400 3875);
FORCEPROP 1 LASTPIN (-2450 3850) $PN 1
J 0
(-2440 3830);
DISPLAY 0.489362 (-2440 3830);
PAINT MONO (-2440 3830);
FORCEPROP 1 LASTPIN (-2450 3650) $PN 2
J 0
(-2440 3630);
DISPLAY 0.489362 (-2440 3630);
PAINT MONO (-2440 3630);
FORCEPROP 1 LAST MATERIAL X6S
J 0
(-2400 3650);
DISPLAY 0.489362 (-2400 3650);
PAINT SKYBLUE (-2400 3650);
FORCEPROP 1 LAST TOLERANCE 20%
J 0
(-2400 3700);
DISPLAY 0.489362 (-2400 3700);
PAINT SKYBLUE (-2400 3700);
FORCEPROP 1 LAST VOLTAGE 4V
J 0
(-2400 3750);
DISPLAY 0.489362 (-2400 3750);
PAINT SKYBLUE (-2400 3750);
FORCEPROP 1 LAST PACK_TYPE C0805
J 0
(-2400 3550);
DISPLAY 0.489362 (-2400 3550);
PAINT SKYBLUE (-2400 3550);
FORCEPROP 1 LAST VALUE 22UF
J 0
(-2400 3800);
DISPLAY 0.489362 (-2400 3800);
PAINT SKYBLUE (-2400 3800);
FORCEPROP 2 LAST CDS_LIB pure_quanta
J 0
(-2450 3750);
DISPLAY INVISIBLE (-2450 3750);
FORCEPROP 1 LAST PATH I37
J 0
(-2400 3900);
DISPLAY 0.978723 (-2400 3900);
PAINT WHITE (-2400 3900);
DISPLAY INVISIBLE (-2400 3900);
FORCEPROP 1 LAST PART_NUMBER CH622KMEA03
J 0
(-2400 3600);
DISPLAY 0.489362 (-2400 3600);
PAINT SKYBLUE (-2400 3600);
DISPLAY INVISIBLE (-2400 3600);
FORCEADD Q_CAP..1
(-2025 3750);
FORCEPROP 1 LAST LOCATION PC83
J 0
(-1975 3850);
DISPLAY 0.489362 (-1975 3850);
PAINT SKYBLUE (-1975 3850);
FORCEPROP 0 LAST $SEC 1
J 0
(-1975 3875);
DISPLAY 0.680851 (-1975 3875);
PAINT MONO (-1975 3875);
DISPLAY INVISIBLE (-1975 3875);
FORCEPROP 0 LAST CDS_SEC 1
J 0
(-1975 3875);
DISPLAY 1.021277 (-1975 3875);
DISPLAY INVISIBLE (-1975 3875);
FORCEPROP 1 LASTPIN (-2025 3850) $PN 1
J 0
(-2015 3830);
DISPLAY 0.489362 (-2015 3830);
PAINT MONO (-2015 3830);
FORCEPROP 1 LASTPIN (-2025 3650) $PN 2
J 0
(-2015 3630);
DISPLAY 0.489362 (-2015 3630);
PAINT MONO (-2015 3630);
FORCEPROP 1 LAST TOLERANCE 20%
J 0
(-1975 3700);
DISPLAY 0.489362 (-1975 3700);
PAINT SKYBLUE (-1975 3700);
FORCEPROP 1 LAST VALUE 22UF
J 0
(-1975 3800);
DISPLAY 0.489362 (-1975 3800);
PAINT SKYBLUE (-1975 3800);
FORCEPROP 1 LAST VOLTAGE 4V
J 0
(-1975 3750);
DISPLAY 0.489362 (-1975 3750);
PAINT SKYBLUE (-1975 3750);
FORCEPROP 1 LAST PACK_TYPE C0805
J 0
(-1975 3600);
DISPLAY 0.489362 (-1975 3600);
PAINT SKYBLUE (-1975 3600);
FORCEPROP 1 LAST MATERIAL X6S
J 0
(-1975 3650);
DISPLAY 0.489362 (-1975 3650);
PAINT SKYBLUE (-1975 3650);
FORCEPROP 2 LAST CDS_LIB pure_quanta
J 0
(-2025 3750);
DISPLAY INVISIBLE (-2025 3750);
FORCEPROP 1 LAST PATH I38
J 0
(-1975 3900);
DISPLAY 0.978723 (-1975 3900);
PAINT WHITE (-1975 3900);
DISPLAY INVISIBLE (-1975 3900);
FORCEPROP 1 LAST PART_NUMBER CH622KMEA03
J 0
(-1975 3600);
DISPLAY 0.489362 (-1975 3600);
PAINT SKYBLUE (-1975 3600);
DISPLAY INVISIBLE (-1975 3600);
FORCEADD Q_RES..1
R 2
(-1450 3225);
FORCEPROP 1 LAST LOCATION PR402
J 2
(-1425 3250);
DISPLAY 0.489362 (-1425 3250);
PAINT SKYBLUE (-1425 3250);
FORCEPROP 0 LAST $SEC 1
J 0
(-1075 3275);
DISPLAY 0.680851 (-1075 3275);
PAINT MONO (-1075 3275);
DISPLAY INVISIBLE (-1075 3275);
FORCEPROP 0 LAST CDS_SEC 1
J 0
(-1075 3275);
DISPLAY 1.021277 (-1075 3275);
DISPLAY INVISIBLE (-1075 3275);
FORCEPROP 1 LASTPIN (-1350 3225) $PN 1
J 2
(-1362 3237);
DISPLAY 0.489362 (-1362 3237);
PAINT MONO (-1362 3237);
FORCEPROP 1 LASTPIN (-1550 3225) $PN 2
J 2
(-1512 3237);
DISPLAY 0.489362 (-1512 3237);
PAINT MONO (-1512 3237);
FORCEPROP 1 LAST PACK_TYPE 0402LF
J 2
(-1200 3175);
DISPLAY 0.489362 (-1200 3175);
PAINT SKYBLUE (-1200 3175);
FORCEPROP 1 LAST WATTAGE 1/16W
J 0
(-1300 3250);
DISPLAY 0.489362 (-1300 3250);
PAINT SKYBLUE (-1300 3250);
FORCEPROP 1 LAST TOLERANCE 1%
J 2
(-1625 3125);
DISPLAY 0.489362 (-1625 3125);
PAINT SKYBLUE (-1625 3125);
FORCEPROP 1 LAST MATERIAL CHIP
J 2
(-1225 3125);
DISPLAY 0.489362 (-1225 3125);
PAINT SKYBLUE (-1225 3125);
FORCEPROP 1 LAST VALUE 49.9
J 0
(-1700 3275);
DISPLAY 0.489362 (-1700 3275);
PAINT SKYBLUE (-1700 3275);
FORCEPROP 2 LAST CDS_LIB pure_quanta
J 2
(-1450 3225);
DISPLAY INVISIBLE (-1450 3225);
FORCEPROP 1 LAST PATH I39
J 2
(-1400 3375);
DISPLAY 0.978723 (-1400 3375);
PAINT WHITE (-1400 3375);
DISPLAY INVISIBLE (-1400 3375);
FORCEPROP 1 LAST PART_NUMBER CS04992FB07
J 2
(-1525 3175);
DISPLAY 0.489362 (-1525 3175);
PAINT SKYBLUE (-1525 3175);
DISPLAY INVISIBLE (-1525 3175);
FORCEADD Q_INDUCTOR..1
(-8450 4800);
FORCEPROP 1 LAST LOCATION PL26
J 0
(-8575 4960);
DISPLAY 0.489362 (-8575 4960);
PAINT SKYBLUE (-8575 4960);
FORCEPROP 0 LAST $SEC 1
J 0
(-8575 5100);
DISPLAY 0.680851 (-8575 5100);
PAINT MONO (-8575 5100);
DISPLAY INVISIBLE (-8575 5100);
FORCEPROP 0 LAST CDS_SEC 1
J 0
(-8575 5100);
DISPLAY 0.680851 (-8575 5100);
DISPLAY INVISIBLE (-8575 5100);
FORCEPROP 0 LASTPIN (-8550 4775) $PN 1
J 2
(-8560 4785);
DISPLAY 0.489362 (-8560 4785);
PAINT MONO (-8560 4785);
FORCEPROP 0 LASTPIN (-8350 4775) $PN 2
J 0
(-8340 4785);
DISPLAY 0.489362 (-8340 4785);
PAINT MONO (-8340 4785);
FORCEPROP 2 LAST PACK_TYPE SMLF
J 0
(-8575 5050);
DISPLAY 0.489362 (-8575 5050);
PAINT SKYBLUE (-8575 5050);
FORCEPROP 1 LAST MATERIAL IND
J 0
(-8575 4855);
DISPLAY 0.489362 (-8575 4855);
PAINT SKYBLUE (-8575 4855);
FORCEPROP 2 LAST VALUE BLM18SN220TN1D/8000MA
J 0
(-8575 5000);
DISPLAY 0.489362 (-8575 5000);
PAINT SKYBLUE (-8575 5000);
FORCEPROP 1 LAST NEEDS_NO_SIZE TRUE
J 0
(-8450 4800);
DISPLAY 0.468085 (-8450 4800);
PAINT GREEN (-8450 4800);
DISPLAY INVISIBLE (-8450 4800);
FORCEPROP 2 LAST CDS_LIB pure_quanta
J 0
(-8450 4800);
DISPLAY INVISIBLE (-8450 4800);
FORCEPROP 1 LAST PATH I4
J 0
(-8375 4855);
DISPLAY 0.723404 (-8375 4855);
PAINT GREEN (-8375 4855);
DISPLAY INVISIBLE (-8375 4855);
FORCEPROP 1 LAST PART_NUMBER CX220TN1001
J 0
(-8575 4910);
DISPLAY 0.489362 (-8575 4910);
PAINT SKYBLUE (-8575 4910);
DISPLAY INVISIBLE (-8575 4910);
FORCEADD Q_CAP..1
(-1825 3750);
FORCEPROP 1 LAST LOCATION PC84
J 0
(-1775 3850);
DISPLAY 0.489362 (-1775 3850);
PAINT SKYBLUE (-1775 3850);
FORCEPROP 0 LAST $SEC 1
J 0
(-1775 3875);
DISPLAY 0.680851 (-1775 3875);
PAINT MONO (-1775 3875);
DISPLAY INVISIBLE (-1775 3875);
FORCEPROP 0 LAST CDS_SEC 1
J 0
(-1775 3875);
DISPLAY 1.021277 (-1775 3875);
DISPLAY INVISIBLE (-1775 3875);
FORCEPROP 1 LASTPIN (-1825 3850) $PN 1
J 0
(-1815 3830);
DISPLAY 0.489362 (-1815 3830);
PAINT MONO (-1815 3830);
FORCEPROP 1 LASTPIN (-1825 3650) $PN 2
J 0
(-1815 3630);
DISPLAY 0.489362 (-1815 3630);
PAINT MONO (-1815 3630);
FORCEPROP 1 LAST VALUE 22UF
J 0
(-1775 3800);
DISPLAY 0.489362 (-1775 3800);
PAINT SKYBLUE (-1775 3800);
FORCEPROP 1 LAST VOLTAGE 4V
J 0
(-1775 3750);
DISPLAY 0.489362 (-1775 3750);
PAINT SKYBLUE (-1775 3750);
FORCEPROP 1 LAST MATERIAL X6S
J 0
(-1775 3650);
DISPLAY 0.489362 (-1775 3650);
PAINT SKYBLUE (-1775 3650);
FORCEPROP 1 LAST PACK_TYPE C0805
J 0
(-1775 3600);
DISPLAY 0.489362 (-1775 3600);
PAINT SKYBLUE (-1775 3600);
FORCEPROP 1 LAST TOLERANCE 20%
J 0
(-1775 3700);
DISPLAY 0.489362 (-1775 3700);
PAINT SKYBLUE (-1775 3700);
FORCEPROP 2 LAST CDS_LIB pure_quanta
J 0
(-1825 3750);
DISPLAY INVISIBLE (-1825 3750);
FORCEPROP 1 LAST PATH I40
J 0
(-1775 3900);
DISPLAY 0.978723 (-1775 3900);
PAINT WHITE (-1775 3900);
DISPLAY INVISIBLE (-1775 3900);
FORCEPROP 1 LAST PART_NUMBER CH622KMEA03
J 0
(-1775 3600);
DISPLAY 0.489362 (-1775 3600);
PAINT SKYBLUE (-1775 3600);
DISPLAY INVISIBLE (-1775 3600);
FORCEADD Q_CAP..1
(-1575 3750);
FORCEPROP 1 LAST LOCATION PC87
J 0
(-1525 3850);
DISPLAY 0.489362 (-1525 3850);
PAINT SKYBLUE (-1525 3850);
FORCEPROP 0 LAST $SEC 1
J 0
(-1525 3875);
DISPLAY 0.680851 (-1525 3875);
PAINT MONO (-1525 3875);
DISPLAY INVISIBLE (-1525 3875);
FORCEPROP 0 LAST CDS_SEC 1
J 0
(-1525 3875);
DISPLAY 1.021277 (-1525 3875);
DISPLAY INVISIBLE (-1525 3875);
FORCEPROP 1 LASTPIN (-1575 3850) $PN 1
J 0
(-1565 3830);
DISPLAY 0.489362 (-1565 3830);
PAINT MONO (-1565 3830);
FORCEPROP 1 LASTPIN (-1575 3650) $PN 2
J 0
(-1565 3630);
DISPLAY 0.489362 (-1565 3630);
PAINT MONO (-1565 3630);
FORCEPROP 1 LAST VOLTAGE 4V
J 0
(-1525 3750);
DISPLAY 0.489362 (-1525 3750);
PAINT SKYBLUE (-1525 3750);
FORCEPROP 1 LAST TOLERANCE 20%
J 0
(-1525 3700);
DISPLAY 0.489362 (-1525 3700);
PAINT SKYBLUE (-1525 3700);
FORCEPROP 1 LAST MATERIAL EMPTY
J 0
(-1525 3650);
DISPLAY 0.489362 (-1525 3650);
PAINT RED (-1525 3650);
FORCEPROP 1 LAST PACK_TYPE C0805
J 0
(-1525 3600);
DISPLAY 0.489362 (-1525 3600);
PAINT SKYBLUE (-1525 3600);
FORCEPROP 1 LAST VALUE 22UF
J 0
(-1525 3800);
DISPLAY 0.489362 (-1525 3800);
PAINT SKYBLUE (-1525 3800);
FORCEPROP 2 LAST CDS_LIB pure_quanta
J 0
(-1575 3750);
DISPLAY INVISIBLE (-1575 3750);
FORCEPROP 1 LAST PATH I41
J 0
(-1525 3900);
DISPLAY 0.978723 (-1525 3900);
PAINT WHITE (-1525 3900);
DISPLAY INVISIBLE (-1525 3900);
FORCEPROP 1 LAST PART_NUMBER CH622KMEA03
J 0
(-1525 3600);
DISPLAY 0.489362 (-1525 3600);
PAINT SKYBLUE (-1525 3600);
DISPLAY INVISIBLE (-1525 3600);
FORCEADD Q_CAP..1
(-1250 3750);
FORCEPROP 1 LAST LOCATION PC88
J 0
(-1200 3850);
DISPLAY 0.489362 (-1200 3850);
PAINT SKYBLUE (-1200 3850);
FORCEPROP 0 LAST $SEC 1
J 0
(-1200 3875);
DISPLAY 0.680851 (-1200 3875);
PAINT MONO (-1200 3875);
DISPLAY INVISIBLE (-1200 3875);
FORCEPROP 0 LAST CDS_SEC 1
J 0
(-1200 3875);
DISPLAY 1.021277 (-1200 3875);
DISPLAY INVISIBLE (-1200 3875);
FORCEPROP 1 LASTPIN (-1250 3850) $PN 1
J 0
(-1240 3830);
DISPLAY 0.489362 (-1240 3830);
PAINT MONO (-1240 3830);
FORCEPROP 1 LASTPIN (-1250 3650) $PN 2
J 0
(-1240 3630);
DISPLAY 0.489362 (-1240 3630);
PAINT MONO (-1240 3630);
FORCEPROP 1 LAST PACK_TYPE C0805
J 0
(-1200 3600);
DISPLAY 0.489362 (-1200 3600);
PAINT SKYBLUE (-1200 3600);
FORCEPROP 1 LAST VOLTAGE 4V
J 0
(-1200 3750);
DISPLAY 0.489362 (-1200 3750);
PAINT SKYBLUE (-1200 3750);
FORCEPROP 1 LAST MATERIAL EMPTY
J 0
(-1200 3650);
DISPLAY 0.489362 (-1200 3650);
PAINT RED (-1200 3650);
FORCEPROP 1 LAST TOLERANCE 20%
J 0
(-1200 3700);
DISPLAY 0.489362 (-1200 3700);
PAINT SKYBLUE (-1200 3700);
FORCEPROP 1 LAST VALUE 22UF
J 0
(-1200 3800);
DISPLAY 0.489362 (-1200 3800);
PAINT SKYBLUE (-1200 3800);
FORCEPROP 2 LAST CDS_LIB pure_quanta
J 0
(-1250 3750);
DISPLAY INVISIBLE (-1250 3750);
FORCEPROP 1 LAST PATH I42
J 0
(-1200 3900);
DISPLAY 0.978723 (-1200 3900);
PAINT WHITE (-1200 3900);
DISPLAY INVISIBLE (-1200 3900);
FORCEPROP 1 LAST PART_NUMBER CH622KMEA03
J 0
(-1200 3600);
DISPLAY 0.489362 (-1200 3600);
PAINT SKYBLUE (-1200 3600);
DISPLAY INVISIBLE (-1200 3600);
FORCEADD Q_CAPP..1
(-975 3725);
FORCEPROP 1 LAST LOCATION PC89
J 0
(-925 3850);
DISPLAY 0.489362 (-925 3850);
PAINT SKYBLUE (-925 3850);
FORCEPROP 0 LAST $SEC 1
J 0
(-925 3900);
DISPLAY 0.680851 (-925 3900);
PAINT MONO (-925 3900);
DISPLAY INVISIBLE (-925 3900);
FORCEPROP 0 LAST CDS_SEC 1
J 0
(-925 3900);
DISPLAY 1.021277 (-925 3900);
DISPLAY INVISIBLE (-925 3900);
FORCEPROP 1 LASTPIN (-975 3825) $PN 1
J 0
(-965 3810);
DISPLAY 0.489362 (-965 3810);
PAINT MONO (-965 3810);
FORCEPROP 1 LASTPIN (-975 3625) $PN 2
J 0
(-965 3610);
DISPLAY 0.489362 (-965 3610);
PAINT MONO (-965 3610);
FORCEPROP 1 LAST VALUE 390UF
J 0
(-925 3800);
DISPLAY 0.489362 (-925 3800);
PAINT SKYBLUE (-925 3800);
FORCEPROP 1 LAST TOLERANCE 20%
J 0
(-925 3750);
DISPLAY 0.489362 (-925 3750);
PAINT SKYBLUE (-925 3750);
FORCEPROP 1 LAST VOLTAGE 2.5V
J 0
(-925 3700);
DISPLAY 0.489362 (-925 3700);
PAINT SKYBLUE (-925 3700);
FORCEPROP 1 LAST PACK_TYPE SMLF
J 0
(-925 3600);
DISPLAY 0.489362 (-925 3600);
PAINT SKYBLUE (-925 3600);
FORCEPROP 1 LAST MATERIAL ALUM
J 0
(-925 3650);
DISPLAY 0.489362 (-925 3650);
PAINT SKYBLUE (-925 3650);
FORCEPROP 2 LAST CDS_LIB pure_quanta
J 0
(-975 3725);
DISPLAY INVISIBLE (-975 3725);
FORCEPROP 1 LAST PATH I43
J 0
(-925 3875);
DISPLAY 0.978723 (-925 3875);
DISPLAY INVISIBLE (-925 3875);
FORCEPROP 1 LAST PART_NUMBER CC7390JMZ13
J 0
(-925 3550);
DISPLAY 0.489362 (-925 3550);
PAINT SKYBLUE (-925 3550);
DISPLAY INVISIBLE (-925 3550);
FORCEADD OFFPAGE..1
R 2
(-725 2500);
FORCEPROP 2 LAST $XR0 54 
J 0
(-449 2500);
DISPLAY 0.638298 (-449 2500);
PAINT MONO (-449 2500);
FORCEPROP 2 LAST CDS_LIB standard
J 0
(-725 2500);
DISPLAY INVISIBLE (-725 2500);
FORCEPROP 1 LAST OFFPAGE TRUE
J 2
(-1050 2375);
DISPLAY 0.872340 (-1050 2375);
PAINT GREEN (-1050 2375);
DISPLAY INVISIBLE (-1050 2375);
FORCEPROP 1 LAST COMMENT_BODY TRUE
J 2
(-850 2400);
DISPLAY 0.872340 (-850 2400);
PAINT GREEN (-850 2400);
DISPLAY INVISIBLE (-850 2400);
FORCEPROP 2 LAST PATH I44
J 0
(-525 2550);
DISPLAY 0.680851 (-525 2550);
DISPLAY INVISIBLE (-525 2550);
FORCEADD OFFPAGE..1
R 2
(-725 2750);
FORCEPROP 2 LAST $XR0 54 
J 0
(-449 2750);
DISPLAY 0.638298 (-449 2750);
PAINT MONO (-449 2750);
FORCEPROP 2 LAST CDS_LIB standard
J 2
(-725 2750);
DISPLAY INVISIBLE (-725 2750);
FORCEPROP 1 LAST OFFPAGE TRUE
J 2
(-1050 2625);
DISPLAY 0.872340 (-1050 2625);
PAINT GREEN (-1050 2625);
DISPLAY INVISIBLE (-1050 2625);
FORCEPROP 1 LAST COMMENT_BODY TRUE
J 2
(-850 2650);
DISPLAY 0.872340 (-850 2650);
PAINT GREEN (-850 2650);
DISPLAY INVISIBLE (-850 2650);
FORCEPROP 2 LAST PATH I45
J 0
(-525 2800);
DISPLAY 0.680851 (-525 2800);
DISPLAY INVISIBLE (-525 2800);
FORCEADD UNIVERSAL_GND..1
(-600 3375);
FORCEPROP 3 LASTPIN (-600 3425) SIG_NAME GND\g
J 0
(-590 3435);
DISPLAY 0.659574 (-590 3435);
PAINT MONO (-590 3435);
DISPLAY INVISIBLE (-590 3435);
FORCEPROP 2 LAST CDS_LIB pure_quanta_power
J 0
(-600 3375);
DISPLAY INVISIBLE (-600 3375);
FORCEPROP 1 LAST HDL_POWER GND
J 1
(-575 3300);
DISPLAY 0.872340 (-575 3300);
PAINT GREEN (-575 3300);
DISPLAY INVISIBLE (-575 3300);
FORCEPROP 1 LAST PATH I46
J 0
(-525 3375);
DISPLAY 0.872340 (-525 3375);
PAINT AQUA (-525 3375);
DISPLAY INVISIBLE (-525 3375);
FORCEADD Q_CAP..1
(-600 3725);
FORCEPROP 1 LAST LOCATION PC21
J 0
(-550 3850);
DISPLAY 0.489362 (-550 3850);
PAINT SKYBLUE (-550 3850);
FORCEPROP 0 LAST $SEC 1
J 0
(-550 3850);
DISPLAY 0.680851 (-550 3850);
PAINT MONO (-550 3850);
DISPLAY INVISIBLE (-550 3850);
FORCEPROP 0 LAST CDS_SEC 1
J 0
(-550 3850);
DISPLAY 1.021277 (-550 3850);
DISPLAY INVISIBLE (-550 3850);
FORCEPROP 1 LASTPIN (-600 3825) $PN 1
J 0
(-590 3805);
DISPLAY 0.489362 (-590 3805);
PAINT MONO (-590 3805);
FORCEPROP 1 LASTPIN (-600 3625) $PN 2
J 0
(-590 3605);
DISPLAY 0.489362 (-590 3605);
PAINT MONO (-590 3605);
FORCEPROP 1 LAST TOLERANCE 10%
J 0
(-550 3700);
DISPLAY 0.489362 (-550 3700);
PAINT SKYBLUE (-550 3700);
FORCEPROP 1 LAST MATERIAL X7R
J 0
(-550 3650);
DISPLAY 0.489362 (-550 3650);
PAINT SKYBLUE (-550 3650);
FORCEPROP 1 LAST PACK_TYPE 0402
J 0
(-550 3550);
DISPLAY 0.489362 (-550 3550);
PAINT SKYBLUE (-550 3550);
FORCEPROP 1 LAST VALUE 0.1UF
J 0
(-550 3800);
DISPLAY 0.489362 (-550 3800);
PAINT SKYBLUE (-550 3800);
FORCEPROP 1 LAST VOLTAGE 25V
J 0
(-550 3750);
DISPLAY 0.489362 (-550 3750);
PAINT SKYBLUE (-550 3750);
FORCEPROP 2 LAST CDS_LIB pure_quanta
J 0
(-600 3725);
DISPLAY INVISIBLE (-600 3725);
FORCEPROP 1 LAST PATH I47
J 0
(-550 3875);
DISPLAY 0.978723 (-550 3875);
PAINT WHITE (-550 3875);
DISPLAY INVISIBLE (-550 3875);
FORCEPROP 1 LAST PART_NUMBER CH4104K1B00
J 0
(-550 3600);
DISPLAY 0.489362 (-550 3600);
PAINT SKYBLUE (-550 3600);
DISPLAY INVISIBLE (-550 3600);
FORCEADD Q_RES..1
(-3575 4500);
FORCEPROP 1 LAST LOCATION R259
J 0
(-3450 4500);
DISPLAY 0.489362 (-3450 4500);
PAINT SKYBLUE (-3450 4500);
FORCEPROP 0 LAST $SEC 1
J 2
(-3450 4550);
DISPLAY 0.680851 (-3450 4550);
PAINT MONO (-3450 4550);
DISPLAY INVISIBLE (-3450 4550);
FORCEPROP 0 LAST CDS_SEC 1
J 2
(-3450 4550);
DISPLAY 1.021277 (-3450 4550);
DISPLAY INVISIBLE (-3450 4550);
FORCEPROP 1 LASTPIN (-3675 4500) $PN 1
J 0
(-3663 4512);
DISPLAY 0.489362 (-3663 4512);
PAINT MONO (-3663 4512);
FORCEPROP 1 LASTPIN (-3475 4500) $PN 2
J 0
(-3513 4512);
DISPLAY 0.489362 (-3513 4512);
PAINT MONO (-3513 4512);
FORCEPROP 1 LAST VALUE 33
J 2
(-3700 4500);
DISPLAY 0.489362 (-3700 4500);
PAINT SKYBLUE (-3700 4500);
FORCEPROP 2 LAST BOM_COST MEM
J 2
(-3550 4650);
DISPLAY 0.744681 (-3550 4650);
PAINT WHITE (-3550 4650);
DISPLAY INVISIBLE (-3550 4650);
FORCEPROP 2 LAST CDS_LIB pure_quanta
J 2
(-3575 4500);
DISPLAY INVISIBLE (-3575 4500);
FORCEPROP 1 LAST WATTAGE 1/16W
J 2
(-3650 4425);
DISPLAY 0.489362 (-3650 4425);
PAINT SKYBLUE (-3650 4425);
DISPLAY INVISIBLE (-3650 4425);
FORCEPROP 1 LAST MATERIAL CHIP
J 2
(-3400 4475);
DISPLAY 0.489362 (-3400 4475);
PAINT SKYBLUE (-3400 4475);
DISPLAY INVISIBLE (-3400 4475);
FORCEPROP 1 LAST TOLERANCE 5%
J 0
(-3700 4475);
DISPLAY 0.489362 (-3700 4475);
PAINT SKYBLUE (-3700 4475);
DISPLAY INVISIBLE (-3700 4475);
FORCEPROP 1 LAST PACK_TYPE 0402LF
J 2
(-3400 4425);
DISPLAY 0.489362 (-3400 4425);
PAINT SKYBLUE (-3400 4425);
DISPLAY INVISIBLE (-3400 4425);
FORCEPROP 1 LAST PATH I48
J 0
(-3625 4650);
DISPLAY 0.978723 (-3625 4650);
PAINT WHITE (-3625 4650);
DISPLAY INVISIBLE (-3625 4650);
FORCEPROP 1 LAST PART_NUMBER CS03302JB10
J 2
(-3475 4550);
DISPLAY 0.489362 (-3475 4550);
PAINT SKYBLUE (-3475 4550);
DISPLAY INVISIBLE (-3475 4550);
FORCEADD OFFPAGE..2
(-1875 4500);
FORCEPROP 2 LAST $XR0 81 
J 0
(-1686 4500);
DISPLAY 0.638298 (-1686 4500);
PAINT MONO (-1686 4500);
FORCEPROP 2 LAST ROOM VR_CORE0_CTRL
J 2
(-1600 4550);
PAINT RED (-1600 4550);
DISPLAY INVISIBLE (-1600 4550);
FORCEPROP 2 LAST CDS_LIB standard
J 0
(-1875 4500);
DISPLAY INVISIBLE (-1875 4500);
FORCEPROP 1 LAST OFFPAGE TRUE
J 0
(-1550 4375);
DISPLAY 1.170213 (-1550 4375);
PAINT GREEN (-1550 4375);
DISPLAY INVISIBLE (-1550 4375);
FORCEPROP 1 LAST COMMENT_BODY TRUE
J 0
(-1920 4405);
DISPLAY 1.170213 (-1920 4405);
PAINT GREEN (-1920 4405);
DISPLAY INVISIBLE (-1920 4405);
FORCEPROP 2 LAST PATH I49
J 0
(-1675 4550);
DISPLAY 0.680851 (-1675 4550);
DISPLAY INVISIBLE (-1675 4550);
FORCEADD P1V0_AUX..1
(-8750 5225);
FORCEPROP 3 LASTPIN (-8750 5175) SIG_NAME P12V_AUX\g
J 0
(-8740 5185);
DISPLAY 0.659574 (-8740 5185);
PAINT MONO (-8740 5185);
DISPLAY INVISIBLE (-8740 5185);
FORCEPROP 1 LAST HDL_POWER P12V_AUX
J 1
(-8725 5275);
DISPLAY 0.489362 (-8725 5275);
PAINT GREEN (-8725 5275);
FORCEPROP 2 LAST ROOM VR_DDR1_POWER_STAGE
J 0
(-8750 5325);
DISPLAY 0.978723 (-8750 5325);
PAINT RED (-8750 5325);
DISPLAY INVISIBLE (-8750 5325);
FORCEPROP 1 LAST VOLTAGE 1.0V
J 0
(-8795 5182);
DISPLAY 0.340426 (-8795 5182);
PAINT SKYBLUE (-8795 5182);
DISPLAY INVISIBLE (-8795 5182);
FORCEPROP 2 LAST CDS_LIB mstr_symbols
J 0
(-8750 5225);
DISPLAY INVISIBLE (-8750 5225);
FORCEPROP 1 LAST BODY_TYPE PLUMBING
J 0
(-8795 5182);
DISPLAY 0.340426 (-8795 5182);
PAINT GREEN (-8795 5182);
DISPLAY INVISIBLE (-8795 5182);
FORCEPROP 1 LAST PATH I5
J 0
(-8700 5250);
DISPLAY 0.872340 (-8700 5250);
PAINT AQUA (-8700 5250);
DISPLAY INVISIBLE (-8700 5250);
FORCEADD Q_RES..2
(50 3750);
FORCEPROP 1 LAST LOCATION PR403
J 0
(95 3875);
DISPLAY 0.489362 (95 3875);
PAINT SKYBLUE (95 3875);
FORCEPROP 0 LAST $SEC 1
J 0
(100 3900);
DISPLAY 0.680851 (100 3900);
PAINT MONO (100 3900);
DISPLAY INVISIBLE (100 3900);
FORCEPROP 0 LAST CDS_SEC 1
J 0
(100 3900);
DISPLAY 1.021277 (100 3900);
DISPLAY INVISIBLE (100 3900);
FORCEPROP 1 LASTPIN (50 3850) $PN 1
J 0
(55 3812);
DISPLAY 0.489362 (55 3812);
PAINT MONO (55 3812);
FORCEPROP 1 LASTPIN (50 3650) $PN 2
J 0
(55 3660);
DISPLAY 0.489362 (55 3660);
PAINT MONO (55 3660);
FORCEPROP 1 LAST WATTAGE 1/16W
J 0
(90 3725);
DISPLAY 0.489362 (90 3725);
PAINT SKYBLUE (90 3725);
FORCEPROP 1 LAST MATERIAL CHIP
J 0
(90 3675);
DISPLAY 0.489362 (90 3675);
PAINT SKYBLUE (90 3675);
FORCEPROP 1 LAST TOLERANCE 1%
J 0
(95 3775);
DISPLAY 0.489362 (95 3775);
PAINT SKYBLUE (95 3775);
FORCEPROP 1 LAST VALUE 1K
J 0
(95 3825);
DISPLAY 0.489362 (95 3825);
PAINT SKYBLUE (95 3825);
FORCEPROP 1 LAST PACK_TYPE 0402LF
J 0
(90 3575);
DISPLAY 0.489362 (90 3575);
PAINT SKYBLUE (90 3575);
FORCEPROP 2 LAST CDS_LIB pure_quanta
J 0
(50 3750);
DISPLAY INVISIBLE (50 3750);
FORCEPROP 1 LAST PATH I50
J 0
(100 3925);
DISPLAY 0.978723 (100 3925);
PAINT WHITE (100 3925);
DISPLAY INVISIBLE (100 3925);
FORCEPROP 1 LAST PART_NUMBER CS21002FB06
J 0
(90 3625);
DISPLAY 0.489362 (90 3625);
PAINT SKYBLUE (90 3625);
DISPLAY INVISIBLE (90 3625);
FORCEADD UNIVERSAL_GND..1
(50 3450);
FORCEPROP 3 LASTPIN (50 3500) SIG_NAME GND\g
J 0
(60 3510);
DISPLAY 0.659574 (60 3510);
PAINT MONO (60 3510);
DISPLAY INVISIBLE (60 3510);
FORCEPROP 2 LAST CDS_LIB pure_quanta_power
J 0
(50 3450);
DISPLAY INVISIBLE (50 3450);
FORCEPROP 1 LAST HDL_POWER GND
J 1
(75 3375);
DISPLAY 0.872340 (75 3375);
PAINT GREEN (75 3375);
DISPLAY INVISIBLE (75 3375);
FORCEPROP 1 LAST PATH I51
J 0
(125 3450);
DISPLAY 0.872340 (125 3450);
PAINT AQUA (125 3450);
DISPLAY INVISIBLE (125 3450);
FORCEADD P1V0..1
(50 4525);
FORCEPROP 3 LASTPIN (50 4475) SIG_NAME PVDD18_S5_P1\g
J 0
(60 4485);
DISPLAY 0.659574 (60 4485);
PAINT MONO (60 4485);
DISPLAY INVISIBLE (60 4485);
FORCEPROP 1 LAST HDL_POWER PVDD18_S5_P1
J 1
(50 4575);
DISPLAY 0.489362 (50 4575);
PAINT GREEN (50 4575);
FORCEPROP 2 LAST CDS_LIB pure_quanta_power
J 0
(50 4525);
PAINT MONO (50 4525);
DISPLAY INVISIBLE (50 4525);
FORCEPROP 1 LAST PATH I52
J 0
(100 4550);
DISPLAY 0.872340 (100 4550);
PAINT AQUA (100 4550);
DISPLAY INVISIBLE (100 4550);
FORCEADD Q_CAP..1
R 2
(-6875 3035);
FORCEPROP 1 LAST LOCATION PC20
J 0
(-6825 3133);
DISPLAY 0.489362 (-6825 3133);
PAINT SKYBLUE (-6825 3133);
FORCEPROP 2 LAST SEC 1
J 0
(-6925 3231);
DISPLAY 0.680851 (-6925 3231);
PAINT MONO (-6925 3231);
DISPLAY INVISIBLE (-6925 3231);
FORCEPROP 1 LASTPIN (-6875 3135) $PN 1
J 2
(-6829 3106);
DISPLAY 0.489362 (-6829 3106);
FORCEPROP 1 LASTPIN (-6875 2935) $PN 2
J 2
(-6831 2930);
DISPLAY 0.489362 (-6831 2930);
FORCEPROP 1 LAST PACK_TYPE C0402
J 0
(-6825 2900);
DISPLAY 0.489362 (-6825 2900);
PAINT SKYBLUE (-6825 2900);
FORCEPROP 1 LAST VOLTAGE 25V
J 0
(-6825 3047);
DISPLAY 0.489362 (-6825 3047);
PAINT SKYBLUE (-6825 3047);
FORCEPROP 1 LAST VALUE 1UF
J 0
(-6825 3096);
DISPLAY 0.489362 (-6825 3096);
PAINT SKYBLUE (-6825 3096);
FORCEPROP 1 LAST TOLERANCE 10%
J 0
(-6825 2998);
DISPLAY 0.489362 (-6825 2998);
PAINT SKYBLUE (-6825 2998);
FORCEPROP 1 LAST MATERIAL X6S
J 0
(-6825 2949);
DISPLAY 0.489362 (-6825 2949);
PAINT SKYBLUE (-6825 2949);
FORCEPROP 2 LAST SEC_TYPE C0402
J 0
(-6925 3231);
DISPLAY 1.021277 (-6925 3231);
DISPLAY INVISIBLE (-6925 3231);
FORCEPROP 2 LAST SIGNAL_MODEL DEFAULT_CAPACITOR_100000PF_2_1
R 3
J 1
(-6945 2983);
DISPLAY 0.744681 (-6945 2983);
PAINT MONO (-6945 2983);
DISPLAY INVISIBLE (-6945 2983);
FORCEPROP 2 LAST CDS_LIB pure_quanta
J 0
(-6875 3035);
DISPLAY INVISIBLE (-6875 3035);
FORCEPROP 1 LAST PATH I53
J 2
(-6925 3185);
DISPLAY 0.978723 (-6925 3185);
PAINT WHITE (-6925 3185);
DISPLAY INVISIBLE (-6925 3185);
FORCEPROP 1 LAST PART_NUMBER CH5104KEB02
J 0
(-6825 2851);
DISPLAY 0.489362 (-6825 2851);
PAINT SKYBLUE (-6825 2851);
DISPLAY INVISIBLE (-6825 2851);
FORCEADD Q_CAP..1
(-7525 4575);
FORCEPROP 1 LAST LOCATION PC60
J 0
(-7475 4675);
DISPLAY 0.489362 (-7475 4675);
PAINT SKYBLUE (-7475 4675);
FORCEPROP 0 LAST $SEC 1
J 0
(-7475 4700);
DISPLAY 0.680851 (-7475 4700);
PAINT MONO (-7475 4700);
DISPLAY INVISIBLE (-7475 4700);
FORCEPROP 0 LAST CDS_SEC 1
J 0
(-7475 4700);
DISPLAY 1.021277 (-7475 4700);
DISPLAY INVISIBLE (-7475 4700);
FORCEPROP 1 LASTPIN (-7525 4675) $PN 1
J 0
(-7515 4655);
DISPLAY 0.489362 (-7515 4655);
PAINT MONO (-7515 4655);
FORCEPROP 1 LASTPIN (-7525 4475) $PN 2
J 0
(-7515 4455);
DISPLAY 0.489362 (-7515 4455);
PAINT MONO (-7515 4455);
FORCEPROP 1 LAST TOLERANCE 20%
J 0
(-7475 4525);
DISPLAY 0.489362 (-7475 4525);
PAINT SKYBLUE (-7475 4525);
FORCEPROP 1 LAST PACK_TYPE C0805
J 0
(-7475 4375);
DISPLAY 0.489362 (-7475 4375);
PAINT SKYBLUE (-7475 4375);
FORCEPROP 1 LAST VOLTAGE 16V
J 0
(-7475 4575);
DISPLAY 0.489362 (-7475 4575);
PAINT SKYBLUE (-7475 4575);
FORCEPROP 1 LAST MATERIAL X6S
J 0
(-7475 4475);
DISPLAY 0.489362 (-7475 4475);
PAINT SKYBLUE (-7475 4475);
FORCEPROP 1 LAST VALUE 22UF
J 0
(-7475 4625);
DISPLAY 0.489362 (-7475 4625);
PAINT SKYBLUE (-7475 4625);
FORCEPROP 2 LAST CDS_LIB pure_quanta
J 0
(-7525 4575);
DISPLAY INVISIBLE (-7525 4575);
FORCEPROP 1 LAST PATH I54
J 0
(-7475 4725);
DISPLAY 0.978723 (-7475 4725);
PAINT WHITE (-7475 4725);
DISPLAY INVISIBLE (-7475 4725);
FORCEPROP 1 LAST PART_NUMBER CH6223MEA01
J 0
(-7475 4425);
DISPLAY 0.489362 (-7475 4425);
PAINT SKYBLUE (-7475 4425);
DISPLAY INVISIBLE (-7475 4425);
FORCEADD Q_CAP..1
(-2375 4350);
FORCEPROP 1 LAST LOCATION C5016
J 0
(-2325 4450);
DISPLAY 0.638298 (-2325 4450);
FORCEPROP 0 LAST $SEC 1
J 0
(-2325 4500);
DISPLAY 0.680851 (-2325 4500);
PAINT MONO (-2325 4500);
DISPLAY INVISIBLE (-2325 4500);
FORCEPROP 0 LAST CDS_SEC 1
J 0
(-2325 4500);
DISPLAY 0.680851 (-2325 4500);
DISPLAY INVISIBLE (-2325 4500);
FORCEPROP 1 LASTPIN (-2375 4450) $PN 1
J 0
(-2365 4430);
DISPLAY 0.787234 (-2365 4430);
PAINT MONO (-2365 4430);
FORCEPROP 1 LASTPIN (-2375 4250) $PN 2
J 0
(-2365 4230);
DISPLAY 0.787234 (-2365 4230);
PAINT MONO (-2365 4230);
FORCEPROP 1 LAST MATERIAL X7R
J 0
(-2325 4250);
DISPLAY 0.638298 (-2325 4250);
FORCEPROP 1 LAST TOLERANCE 5%
J 0
(-2325 4300);
DISPLAY 0.638298 (-2325 4300);
FORCEPROP 1 LAST PACK_TYPE 0402
J 0
(-2325 4150);
DISPLAY 0.638298 (-2325 4150);
FORCEPROP 1 LAST VALUE 1000PF
J 0
(-2325 4400);
DISPLAY 0.638298 (-2325 4400);
FORCEPROP 1 LAST VOLTAGE 50V
J 0
(-2325 4350);
DISPLAY 0.638298 (-2325 4350);
FORCEPROP 2 LAST CDS_LIB pure_quanta
J 0
(-2375 4350);
DISPLAY INVISIBLE (-2375 4350);
FORCEPROP 1 LAST PATH I55
J 0
(-2325 4500);
DISPLAY 0.978723 (-2325 4500);
PAINT WHITE (-2325 4500);
DISPLAY INVISIBLE (-2325 4500);
FORCEPROP 1 LAST PART_NUMBER TMP_QCH21006JB10
J 0
(-2325 4200);
DISPLAY 0.638298 (-2325 4200);
DISPLAY INVISIBLE (-2325 4200);
FORCEADD UNIVERSAL_GND..1
(-2375 4150);
FORCEPROP 3 LASTPIN (-2375 4200) SIG_NAME GND\g
J 0
(-2365 4210);
DISPLAY 0.659574 (-2365 4210);
PAINT MONO (-2365 4210);
DISPLAY INVISIBLE (-2365 4210);
FORCEPROP 2 LAST CDS_LIB pure_quanta_power
J 0
(-2375 4150);
DISPLAY INVISIBLE (-2375 4150);
FORCEPROP 1 LAST HDL_POWER GND
J 1
(-2350 4075);
DISPLAY 0.872340 (-2350 4075);
PAINT GREEN (-2350 4075);
DISPLAY INVISIBLE (-2350 4075);
FORCEPROP 1 LAST PATH I56
J 0
(-2300 4150);
DISPLAY 0.872340 (-2300 4150);
PAINT AQUA (-2300 4150);
DISPLAY INVISIBLE (-2300 4150);
FORCEADD Q_CAP..1
(-7850 4575);
FORCEPROP 1 LAST LOCATION PC8003
J 0
(-7800 4675);
DISPLAY 0.489362 (-7800 4675);
PAINT SKYBLUE (-7800 4675);
FORCEPROP 0 LAST $SEC 1
J 0
(-7800 4700);
DISPLAY 0.680851 (-7800 4700);
PAINT MONO (-7800 4700);
DISPLAY INVISIBLE (-7800 4700);
FORCEPROP 0 LAST CDS_SEC 1
J 0
(-7800 4700);
DISPLAY 0.680851 (-7800 4700);
DISPLAY INVISIBLE (-7800 4700);
FORCEPROP 1 LASTPIN (-7850 4675) $PN 1
J 0
(-7840 4655);
DISPLAY 0.787234 (-7840 4655);
PAINT MONO (-7840 4655);
FORCEPROP 1 LASTPIN (-7850 4475) $PN 2
J 0
(-7840 4455);
DISPLAY 0.787234 (-7840 4455);
PAINT MONO (-7840 4455);
FORCEPROP 1 LAST VALUE 22UF
J 0
(-7800 4625);
DISPLAY 0.489362 (-7800 4625);
PAINT SKYBLUE (-7800 4625);
FORCEPROP 1 LAST MATERIAL X6S
J 0
(-7800 4475);
DISPLAY 0.489362 (-7800 4475);
PAINT SKYBLUE (-7800 4475);
FORCEPROP 1 LAST TOLERANCE 20%
J 0
(-7800 4525);
DISPLAY 0.489362 (-7800 4525);
PAINT SKYBLUE (-7800 4525);
FORCEPROP 1 LAST PACK_TYPE C0805
J 0
(-7800 4375);
DISPLAY 0.489362 (-7800 4375);
PAINT SKYBLUE (-7800 4375);
FORCEPROP 1 LAST VOLTAGE 16V
J 0
(-7800 4575);
DISPLAY 0.489362 (-7800 4575);
PAINT SKYBLUE (-7800 4575);
FORCEPROP 2 LAST CDS_LIB pure_quanta
J 0
(-7850 4575);
DISPLAY INVISIBLE (-7850 4575);
FORCEPROP 1 LAST PATH I57
J 0
(-7800 4725);
DISPLAY 0.978723 (-7800 4725);
PAINT WHITE (-7800 4725);
DISPLAY INVISIBLE (-7800 4725);
FORCEPROP 1 LAST PART_NUMBER CH6223MEA01
J 0
(-7800 4425);
DISPLAY 0.489362 (-7800 4425);
PAINT SKYBLUE (-7800 4425);
DISPLAY INVISIBLE (-7800 4425);
FORCEADD Q_RES..1
(-4250 4300);
FORCEPROP 1 LAST LOCATION PR8002
J 0
(-4450 4300);
DISPLAY 0.510638 (-4450 4300);
FORCEPROP 2 LAST SEC 1
J 0
(-4300 4500);
DISPLAY 0.680851 (-4300 4500);
PAINT MONO (-4300 4500);
DISPLAY INVISIBLE (-4300 4500);
FORCEPROP 1 LASTPIN (-4350 4300) $PN 1
J 0
(-4338 4312);
DISPLAY 0.787234 (-4338 4312);
PAINT MONO (-4338 4312);
FORCEPROP 1 LASTPIN (-4150 4300) $PN 2
J 0
(-4188 4312);
DISPLAY 0.787234 (-4188 4312);
PAINT MONO (-4188 4312);
FORCEPROP 1 LAST TOLERANCE 1%
J 0
(-4175 4250);
DISPLAY 0.638298 (-4175 4250);
FORCEPROP 1 LAST VALUE 2.2
J 2
(-4300 4250);
DISPLAY 0.638298 (-4300 4250);
FORCEPROP 1 LAST PACK_TYPE 0402LF
J 0
(-4400 4350);
DISPLAY 0.510638 (-4400 4350);
FORCEPROP 1 LAST MATERIAL CHIP
J 0
(-4225 4350);
DISPLAY 0.510638 (-4225 4350);
FORCEPROP 2 LAST CDS_LIB pure_quanta
J 0
(-4250 4300);
DISPLAY INVISIBLE (-4250 4300);
FORCEPROP 1 LAST WATTAGE 1/16W
J 2
(-4000 4375);
DISPLAY 0.510638 (-4000 4375);
DISPLAY INVISIBLE (-4000 4375);
FORCEPROP 2 LAST SEC_TYPE 0402LF
J 0
(-4300 4500);
DISPLAY 0.680851 (-4300 4500);
DISPLAY INVISIBLE (-4300 4500);
FORCEPROP 1 LAST PATH I58
J 0
(-4300 4450);
DISPLAY 0.978723 (-4300 4450);
PAINT WHITE (-4300 4450);
DISPLAY INVISIBLE (-4300 4450);
FORCEPROP 1 LAST PART_NUMBER CS-2202FB01
J 0
(-4400 4375);
DISPLAY 0.510638 (-4400 4375);
DISPLAY INVISIBLE (-4400 4375);
FORCEADD Q_CAP..1
R 2
(-7725 3850);
FORCEPROP 1 LAST LOCATION C675
J 2
(-7775 3950);
DISPLAY 0.489362 (-7775 3950);
PAINT SKYBLUE (-7775 3950);
FORCEPROP 0 LAST $SEC 1
J 0
(-7775 4000);
DISPLAY 0.680851 (-7775 4000);
PAINT MONO (-7775 4000);
DISPLAY INVISIBLE (-7775 4000);
FORCEPROP 0 LAST CDS_SEC 1
J 0
(-7775 4000);
DISPLAY 0.680851 (-7775 4000);
DISPLAY INVISIBLE (-7775 4000);
FORCEPROP 1 LASTPIN (-7725 3950) $PN 1
J 2
(-7735 3930);
DISPLAY 0.489362 (-7735 3930);
PAINT MONO (-7735 3930);
FORCEPROP 1 LASTPIN (-7725 3750) $PN 2
J 2
(-7735 3730);
DISPLAY 0.489362 (-7735 3730);
PAINT MONO (-7735 3730);
FORCEPROP 1 LAST PACK_TYPE 0402
J 2
(-7775 3650);
DISPLAY 0.489362 (-7775 3650);
PAINT SKYBLUE (-7775 3650);
FORCEPROP 1 LAST VOLTAGE 25V
J 2
(-7775 3850);
DISPLAY 0.489362 (-7775 3850);
PAINT SKYBLUE (-7775 3850);
FORCEPROP 1 LAST MATERIAL EMPTY
J 2
(-7775 3750);
DISPLAY 0.489362 (-7775 3750);
PAINT RED (-7775 3750);
FORCEPROP 1 LAST VALUE 0.1UF
J 2
(-7775 3900);
DISPLAY 0.489362 (-7775 3900);
PAINT SKYBLUE (-7775 3900);
FORCEPROP 1 LAST TOLERANCE 10%
J 2
(-7775 3800);
DISPLAY 0.489362 (-7775 3800);
PAINT SKYBLUE (-7775 3800);
FORCEPROP 2 LAST CDS_LIB pure_quanta
J 0
(-7725 3850);
DISPLAY INVISIBLE (-7725 3850);
FORCEPROP 1 LAST PATH I6
J 2
(-7775 4000);
DISPLAY 0.978723 (-7775 4000);
PAINT WHITE (-7775 4000);
DISPLAY INVISIBLE (-7775 4000);
FORCEPROP 1 LAST PART_NUMBER CH4104K1B00
J 2
(-7800 3700);
DISPLAY 0.489362 (-7800 3700);
PAINT SKYBLUE (-7800 3700);
DISPLAY INVISIBLE (-7800 3700);
FORCEADD UNIVERSAL_GND..1
(-7725 3650);
FORCEPROP 3 LASTPIN (-7725 3700) SIG_NAME GND\g
J 0
(-7715 3710);
DISPLAY 0.659574 (-7715 3710);
PAINT MONO (-7715 3710);
DISPLAY INVISIBLE (-7715 3710);
FORCEPROP 2 LAST CDS_LIB pure_quanta_power
J 0
(-7725 3650);
DISPLAY INVISIBLE (-7725 3650);
FORCEPROP 1 LAST HDL_POWER GND
J 1
(-7700 3575);
DISPLAY 0.872340 (-7700 3575);
PAINT GREEN (-7700 3575);
DISPLAY INVISIBLE (-7700 3575);
FORCEPROP 1 LAST PATH I7
J 0
(-7650 3650);
DISPLAY 0.872340 (-7650 3650);
PAINT AQUA (-7650 3650);
DISPLAY INVISIBLE (-7650 3650);
FORCEADD UNIVERSAL_GND..1
(-7450 3450);
FORCEPROP 3 LASTPIN (-7450 3500) SIG_NAME GND\g
J 0
(-7440 3510);
DISPLAY 0.659574 (-7440 3510);
PAINT MONO (-7440 3510);
DISPLAY INVISIBLE (-7440 3510);
FORCEPROP 2 LAST CDS_LIB pure_quanta_power
J 0
(-7450 3450);
DISPLAY INVISIBLE (-7450 3450);
FORCEPROP 1 LAST HDL_POWER GND
J 1
(-7425 3375);
DISPLAY 0.872340 (-7425 3375);
PAINT GREEN (-7425 3375);
DISPLAY INVISIBLE (-7425 3375);
FORCEPROP 1 LAST PATH I8
J 0
(-7375 3450);
DISPLAY 0.872340 (-7375 3450);
PAINT AQUA (-7375 3450);
DISPLAY INVISIBLE (-7375 3450);
FORCEADD UNIVERSAL_GND..1
(-6875 2750);
FORCEPROP 3 LASTPIN (-6875 2800) SIG_NAME GND\g
J 0
(-6865 2810);
DISPLAY 0.659574 (-6865 2810);
PAINT MONO (-6865 2810);
DISPLAY INVISIBLE (-6865 2810);
FORCEPROP 2 LAST CDS_LIB pure_quanta_power
J 0
(-6875 2750);
DISPLAY INVISIBLE (-6875 2750);
FORCEPROP 1 LAST HDL_POWER GND
J 1
(-6850 2675);
DISPLAY 0.872340 (-6850 2675);
PAINT GREEN (-6850 2675);
DISPLAY INVISIBLE (-6850 2675);
FORCEPROP 1 LAST PATH I9
J 0
(-6800 2750);
DISPLAY 0.872340 (-6800 2750);
PAINT AQUA (-6800 2750);
DISPLAY INVISIBLE (-6800 2750);
FORCEADD DNS..1
(-7750 3750);
PAINT RED (-7750 3750);
FORCEPROP 2 LAST CDS_LIB mstr_misc
J 0
(-7750 3750);
DISPLAY INVISIBLE (-7750 3750);
FORCEPROP 1 LAST COMMENT_BODY TRUE
J 0
(-7750 3750);
DISPLAY INVISIBLE (-7750 3750);
FORCEADD DNS..1
(-2775 2625);
PAINT RED (-2775 2625);
FORCEPROP 2 LAST CDS_LIB mstr_misc
J 0
(-2775 2625);
DISPLAY INVISIBLE (-2775 2625);
FORCEPROP 1 LAST COMMENT_BODY TRUE
R 1
J 0
(-2700 2400);
DISPLAY 0.872340 (-2700 2400);
PAINT GREEN (-2700 2400);
DISPLAY INVISIBLE (-2700 2400);
FORCEADD DNS..1
(-1525 3750);
PAINT RED (-1525 3750);
FORCEPROP 2 LAST CDS_LIB mstr_misc
J 0
(-1525 3750);
DISPLAY INVISIBLE (-1525 3750);
FORCEPROP 1 LAST COMMENT_BODY TRUE
R 1
J 0
(-1450 3525);
DISPLAY 0.872340 (-1450 3525);
PAINT GREEN (-1450 3525);
DISPLAY INVISIBLE (-1450 3525);
FORCEADD DNS..1
(-1225 3750);
PAINT RED (-1225 3750);
FORCEPROP 2 LAST CDS_LIB mstr_misc
J 0
(-1225 3750);
DISPLAY INVISIBLE (-1225 3750);
FORCEPROP 1 LAST COMMENT_BODY TRUE
R 1
J 0
(-1150 3525);
DISPLAY 0.872340 (-1150 3525);
PAINT GREEN (-1150 3525);
DISPLAY INVISIBLE (-1150 3525);
FORCEADD QUANTA_TITLE_BLOCK_C..1
(425 550);
FORCEPROP 0 LAST CDS_CON_LAST_MODIFIED Thu Sep 14 16:12:17 2023
J 0
(-1460 565);
DISPLAY INVISIBLE (-1460 565);
FORCEPROP 1 LAST CUSTOM_TXT_CDS <CON_LAST_MODIFIED>
J 0
(-1460 565);
DISPLAY 0.978723 (-1460 565);
FORCEPROP 2 LAST CUSTOM_TXT_CDS <XR_PAGE_TITLE>
J 0
(-7465 5800);
DISPLAY 0.638298 (-7465 5800);
PAINT PINK (-7465 5800);
DISPLAY INVISIBLE (-7465 5800);
FORCEPROP 1 LAST CUSTOM_TXT_CDS <NAME_2>
J 0
(-2750 600);
FORCEPROP 1 LAST CUSTOM_TXT_CDS <NAME_1>
J 0
(-2750 725);
FORCEPROP 1 LAST CUSTOM_TXT_CDS <Q_NUMBER>
J 0
(-978 653);
DISPLAY 1.212766 (-978 653);
FORCEPROP 1 LAST CUSTOM_TXT_CDS <Q_PROJ>
J 0
(-1957 652);
DISPLAY 1.212766 (-1957 652);
FORCEPROP 1 LAST CUSTOM_TXT_CDS <Q_REV>
J 0
(241 653);
DISPLAY 1.212766 (241 653);
FORCEPROP 1 LAST CUSTOM_TXT_CDS <CON_PAGE_NUM> OF <CON_TOTAL_PAGES>
J 0
(-21 568);
DISPLAY 0.978723 (-21 568);
FORCEPROP 1 LAST Q_TITLE PVDD18_S5_P1
J 0
(-8875 600);
DISPLAY 2.446809 (-8875 600);
PAINT GREEN (-8875 600);
FORCEPROP 2 LAST CDS_LIB pure_quanta
J 0
(425 550);
DISPLAY INVISIBLE (425 550);
FORCEPROP 1 LAST CDS_LMAN_SYM_OUTLINE -9475,6775,100,-125
J 0
(425 550);
DISPLAY 0.468085 (425 550);
PAINT GREEN (425 550);
DISPLAY INVISIBLE (425 550);
FORCEPROP 2 LAST PAGE_BORDER TRUE
J 0
(-7465 5800);
DISPLAY 0.638298 (-7465 5800);
PAINT PINK (-7465 5800);
DISPLAY INVISIBLE (-7465 5800);
FORCEPROP 2 LAST CDS_XR_PAGE_TITLE CR-226 : @T6G_MB_LIB.T6G(SCH_1):PAGE226
J 0
(-7465 5800);
DISPLAY 0.638298 (-7465 5800);
PAINT PINK (-7465 5800);
DISPLAY INVISIBLE (-7465 5800);
FORCEPROP 1 LAST Q_DEPT BU9
J 1
(-3338 599);
DISPLAY 1.957447 (-3338 599);
PAINT GREEN (-3338 599);
DISPLAY INVISIBLE (-3338 599);
FORCEPROP 1 LAST COMMENT_BODY TRUE
J 0
(437 537);
DISPLAY 0.978723 (437 537);
PAINT GREEN (437 537);
DISPLAY INVISIBLE (437 537);
WIRE 16 -1 (-6375 2875)(-6375 2775);
WIRE 16 -1 (-6875 3550)(-6875 3500);
WIRE 16 -1 (-4700 2925)(-4700 3025);
WIRE 16 -1 (-8800 4475)(-8800 4275);
WIRE 16 -1 (-4375 5025)(-4375 4900);
WIRE 16 -1 (-3300 2250)(-3300 2175);
WIRE 16 -1 (50 3500)(50 3650);
WIRE 16 -1 (-2375 4250)(-2375 4200);
WIRE 16 -1 (-7725 3700)(-7725 3750);
WIRE 16 -1 (-6950 3800)(-7450 3800);
WIRE 16 -1 (-7450 3800)(-7450 3500);
WIRE 16 -1 (-6875 2800)(-6875 2935);
WIRE 17 273 (-8600 1800)(-6425 1800);
WIRE 17 273 (-8600 2275)(-8600 1800);
WIRE 17 273 (-6425 2275)(-6425 1800);
WIRE 17 273 (-8600 2275)(-6425 2275);
WIRE 16 -1 (-8800 4675)(-8800 4775);
WIRE 16 -1 (-8750 4775)(-8800 4775);
WIRE 16 -1 (-8750 5175)(-8750 4775);
WIRE 16 -1 (-8550 4775)(-8750 4775);
WIRE 17 273 (-1200 7050)(375 7050);
WIRE 17 273 (-1200 7050)(-1200 6075);
WIRE 17 273 (375 7050)(375 6075);
WIRE 17 273 (-1200 6075)(375 6075);
WIRE 17 273 (-8600 1125)(-6425 1125);
WIRE 17 273 (-8600 1725)(-8600 1125);
WIRE 17 273 (-6425 1725)(-6425 1125);
WIRE 17 273 (-8600 1725)(-6425 1725);
WIRE 16 -1 (-150 3925)(-150 3225);
WIRE 16 -1 (-600 3925)(-150 3925);
WIRE 16 -1 (-150 3225)(-1350 3225);
WIRE 16 -1 (-600 4000)(-600 3925);
WIRE 16 -1 (-600 3925)(-600 3825);
WIRE 16 -1 (50 4000)(-600 4000);
WIRE 16 -1 (-600 4000)(-975 4000);
WIRE 16 -1 (-975 3825)(-975 4000);
WIRE 16 -1 (-975 4000)(-1250 4000);
WIRE 16 -1 (50 4000)(50 4475);
WIRE 16 -1 (50 4000)(50 3850);
WIRE 16 -1 (-1250 4000)(-1250 3850);
WIRE 16 -1 (-1575 4000)(-1250 4000);
WIRE 16 -1 (-1575 4000)(-1575 3850);
WIRE 16 -1 (-1825 4000)(-1575 4000);
WIRE 16 -1 (-1825 3850)(-1825 4000);
WIRE 16 -1 (-2025 4000)(-1825 4000);
WIRE 16 -1 (-2025 3850)(-2025 4000);
WIRE 16 -1 (-2450 4000)(-2025 4000);
WIRE 16 -1 (-2450 3850)(-2450 4000);
WIRE 16 -1 (-2450 4000)(-3175 4000);
WIRE 16 -1 (-2450 3650)(-2450 3500);
WIRE 16 -1 (-2450 3500)(-2025 3500);
WIRE 16 -1 (-2025 3650)(-2025 3500);
WIRE 16 -1 (-2025 3500)(-1825 3500);
WIRE 16 -1 (-1825 3650)(-1825 3500);
WIRE 16 -1 (-1825 3500)(-1575 3500);
WIRE 16 -1 (-1250 3500)(-1575 3500);
WIRE 16 -1 (-1575 3650)(-1575 3500);
WIRE 16 -1 (-975 3500)(-1250 3500);
WIRE 16 -1 (-1250 3650)(-1250 3500);
WIRE 16 -1 (-975 3625)(-975 3500);
WIRE 16 -1 (-600 3500)(-975 3500);
WIRE 16 -1 (-600 3500)(-600 3625);
WIRE 16 -1 (-600 3425)(-600 3500);
WIRE 16 -1 (-6325 4450)(-6325 4328);
WIRE 16 -1 (-6325 4328)(-6575 4328);
WIRE 16 -1 (-6575 4450)(-6575 4328);
WIRE 16 -1 (-6825 4328)(-6575 4328);
WIRE 16 -1 (-6825 4450)(-6825 4328);
WIRE 16 -1 (-7150 4328)(-6825 4328);
WIRE 16 -1 (-7150 4450)(-7150 4328);
WIRE 16 -1 (-7525 4328)(-7150 4328);
WIRE 16 -1 (-7525 4475)(-7525 4328);
WIRE 16 -1 (-7750 4328)(-7525 4328);
WIRE 16 -1 (-7750 4225)(-7750 4328);
WIRE 16 -1 (-7850 4328)(-7750 4328);
WIRE 16 -1 (-7850 4475)(-7850 4328);
WIRE 16 -1 (-4875 3200)(-5025 3200);
WIRE 16 -1 (-4875 3150)(-4875 3200);
WIRE 16 -1 (-5025 3150)(-4875 3150);
WIRE 16 -1 (-4875 2925)(-4875 3150);
WIRE 16 -1 (-2925 3275)(-2925 3550);
WIRE 16 -1 (-2925 3275)(-3175 3275);
WIRE 16 -1 (-2925 3550)(-2750 3550);
WIRE 16 -1 (-3175 3550)(-2925 3550);
WIRE 16 -1 (-2750 3550)(-2600 3550);
WIRE 16 -1 (-2750 2750)(-2750 3550);
WIRE 16 -1 (-2750 2750)(-2250 2750);
WIRE 16 -1 (-2750 2750)(-2750 2725);
WIRE 16 -1 (-2600 3550)(-2600 3225);
WIRE 16 -1 (-2600 3225)(-1550 3225);
FORCEPROP 2 LAST SIG_NAME PVDD18_S5_P1_FB_RC
J 0
(-2310 3235);
DISPLAY 0.489362 (-2310 3235);
FORCEPROP 2 LASTPROP $XRERR UNIQUE?
J 0
(-2550 3235);
DISPLAY 0.638298 (-2550 3235);
PAINT MONO (-2550 3235);
DISPLAY INVISIBLE (-2550 3235);
WIRE 16 -1 (-3775 4025)(-3775 4000);
WIRE 16 -1 (-3775 4000)(-3375 4000);
WIRE 16 -1 (-5025 4000)(-3775 4000);
FORCEPROP 2 LAST SIG_NAME SW_PVDD18_S5_P1_SW
J 0
(-4920 4017);
DISPLAY 0.489362 (-4920 4017);
FORCEPROP 2 LASTPROP $XRERR UNIQUE?
J 0
(-5160 4017);
DISPLAY 0.638298 (-5160 4017);
PAINT MONO (-5160 4017);
DISPLAY INVISIBLE (-5160 4017);
WIRE 16 -1 (-3775 4300)(-3775 4225);
WIRE 16 -1 (-4150 4300)(-3775 4300);
FORCEPROP 2 LAST SIG_NAME SW_PVDD18_S5_P1_BST_R
J 0
(-4135 4310);
DISPLAY 0.361702 (-4135 4310);
FORCEPROP 2 LASTPROP $XRERR UNIQUE?
J 0
(-4375 4310);
DISPLAY 0.638298 (-4375 4310);
PAINT MONO (-4375 4310);
DISPLAY INVISIBLE (-4375 4310);
WIRE 16 -1 (-3375 3275)(-3650 3275);
WIRE 16 -1 (-3650 3550)(-3650 3275);
WIRE 16 -1 (-3375 3550)(-3650 3550);
WIRE 16 -1 (-3650 3550)(-3875 3550);
WIRE 16 -1 (-3875 3350)(-3875 3550);
WIRE 16 -1 (-5025 3550)(-3875 3550);
FORCEPROP 2 LAST SIG_NAME PVDD18_S5_P1_FB
J 0
(-4935 3575);
DISPLAY 0.489362 (-4935 3575);
FORCEPROP 2 LASTPROP $XRERR UNIQUE?
J 0
(-5175 3575);
DISPLAY 0.638298 (-5175 3575);
PAINT MONO (-5175 3575);
DISPLAY INVISIBLE (-5175 3575);
WIRE 16 -1 (-5025 4300)(-4350 4300);
FORCEPROP 2 LAST SIG_NAME SW_PVDD18_S5_P1_BST
J 0
(-4935 4325);
DISPLAY 0.489362 (-4935 4325);
FORCEPROP 2 LASTPROP $XRERR UNIQUE?
J 0
(-5175 4325);
DISPLAY 0.638298 (-5175 4325);
PAINT MONO (-5175 4325);
DISPLAY INVISIBLE (-5175 4325);
WIRE 16 -1 (-2750 2525)(-2750 2500);
WIRE 16 -1 (-2250 2500)(-2750 2500);
WIRE 16 -1 (-3300 2500)(-2750 2500);
WIRE 16 -1 (-3300 2450)(-3300 2500);
WIRE 16 -1 (-3300 2500)(-3875 2500);
WIRE 16 -1 (-3875 2500)(-3875 2950);
WIRE 16 -1 (-3875 3150)(-3875 2950);
WIRE 16 -1 (-4000 2950)(-3875 2950);
WIRE 16 -1 (-4000 3300)(-4000 2950);
WIRE 16 -1 (-4000 3400)(-4000 3300);
WIRE 16 -1 (-4175 3300)(-4000 3300);
WIRE 16 -1 (-5025 3400)(-4000 3400);
FORCEPROP 2 LAST SIG_NAME PVDD18_SS_P1_RGND
J 0
(-4935 3410);
DISPLAY 0.489362 (-4935 3410);
FORCEPROP 2 LASTPROP $XRERR UNIQUE?
J 0
(-5175 3410);
DISPLAY 0.638298 (-5175 3410);
PAINT MONO (-5175 3410);
DISPLAY INVISIBLE (-5175 3410);
WIRE 16 -1 (-4375 4700)(-4375 4500);
WIRE 16 -1 (-4375 4500)(-3675 4500);
FORCEPROP 2 LAST SIG_NAME PWRGD_PVDD18_S5_P1
J 0
(-4210 4510);
DISPLAY 0.489362 (-4210 4510);
FORCEPROP 2 LASTPROP $XRERR UNIQUE?
J 0
(-4450 4510);
DISPLAY 0.638298 (-4450 4510);
PAINT MONO (-4450 4510);
DISPLAY INVISIBLE (-4450 4510);
WIRE 16 -1 (-5025 4500)(-4375 4500);
WIRE 16 -1 (-6000 4450)(-5825 4450);
WIRE 16 -1 (-6000 4500)(-6000 4450);
WIRE 16 -1 (-6000 4775)(-6000 4500);
WIRE 16 -1 (-6000 4500)(-5825 4500);
WIRE 16 -1 (-6325 4775)(-6000 4775);
WIRE 16 -1 (-6325 4650)(-6325 4775);
WIRE 16 -1 (-6575 4775)(-6325 4775);
WIRE 16 -1 (-6575 4650)(-6575 4775);
WIRE 16 -1 (-6825 4775)(-6575 4775);
WIRE 16 -1 (-6825 4650)(-6825 4775);
WIRE 16 -1 (-7150 4775)(-6825 4775);
WIRE 16 -1 (-7150 4650)(-7150 4775);
WIRE 16 -1 (-7525 4775)(-7150 4775);
FORCEPROP 2 LAST SIG_NAME SW_P12V_AUX_PVDD18_S5_P1_FLT
J 0
(-7187 4798);
DISPLAY 0.489362 (-7187 4798);
FORCEPROP 2 LASTPROP $XRERR UNIQUE?
J 0
(-7427 4798);
DISPLAY 0.638298 (-7427 4798);
PAINT MONO (-7427 4798);
DISPLAY INVISIBLE (-7427 4798);
WIRE 16 -1 (-7525 4675)(-7525 4775);
WIRE 16 -1 (-7850 4775)(-7525 4775);
WIRE 16 -1 (-7850 4775)(-7850 4675);
WIRE 16 -1 (-8350 4775)(-7850 4775);
WIRE 16 -1 (-7725 4000)(-5825 4000);
WIRE 16 -1 (-7725 4000)(-7725 3950);
WIRE 16 -1 (-8475 4000)(-7725 4000);
FORCEPROP 2 LAST SIG_NAME PVDD18_S5_P1_EN
J 0
(-8435 4010);
DISPLAY 0.489362 (-8435 4010);
WIRE 17 273 (-2475 3000)(-150 3000);
WIRE 17 273 (-2475 3000)(-2475 2125);
WIRE 17 273 (-150 3000)(-150 2125);
WIRE 17 273 (-2475 2125)(-150 2125);
WIRE 16 -1 (-2050 2500)(-775 2500);
FORCEPROP 2 LAST SIG_NAME VSENSE_PVDD18_S5_P1_DN
J 0
(-1560 2510);
DISPLAY 0.489362 (-1560 2510);
WIRE 17 273 (-1675 2875)(-475 2875);
WIRE 17 273 (-1675 2875)(-1675 2375);
WIRE 17 273 (-475 2875)(-475 2375);
WIRE 17 273 (-1675 2375)(-475 2375);
WIRE 16 -1 (-2050 2750)(-775 2750);
FORCEPROP 2 LAST SIG_NAME VSENSE_PVDD18_S5_P1_DP
J 0
(-1560 2760);
DISPLAY 0.489362 (-1560 2760);
WIRE 16 -1 (-2375 4450)(-2375 4500);
WIRE 16 -1 (-2375 4500)(-1925 4500);
WIRE 16 -1 (-3475 4500)(-2375 4500);
FORCEPROP 2 LAST SIG_NAME PWRGD_PVDD18_S5_R_P1
J 0
(-3310 4510);
DISPLAY 0.489362 (-3310 4510);
WIRE 16 -1 (-2269 2751)(-2269 2752);
WIRE 16 -1 (-3182 2272)(-3182 2273);
WIRE 16 -1 (-4700 3225)(-4700 3300);
WIRE 16 -1 (-4375 3300)(-4700 3300);
WIRE 16 -1 (-5025 3300)(-4700 3300);
FORCEPROP 2 LAST SIG_NAME PVDD18_S5_P1_REF
J 0
(-4935 3310);
DISPLAY 0.489362 (-4935 3310);
FORCEPROP 2 LASTPROP $XRERR UNIQUE?
J 0
(-5175 3310);
DISPLAY 0.638298 (-5175 3310);
PAINT MONO (-5175 3310);
DISPLAY INVISIBLE (-5175 3310);
WIRE 16 -1 (-5825 3800)(-6750 3800);
FORCEPROP 2 LAST SIG_NAME PVDD18_S5_P1_MODE
J 0
(-6635 3810);
DISPLAY 0.489362 (-6635 3810);
FORCEPROP 2 LASTPROP $XRERR UNIQUE?
J 0
(-6875 3810);
DISPLAY 0.638298 (-6875 3810);
PAINT MONO (-6875 3810);
DISPLAY INVISIBLE (-6875 3810);
WIRE 16 -1 (-6875 3300)(-6875 3200);
WIRE 16 -1 (-6875 3200)(-6550 3200);
WIRE 16 -1 (-6875 3135)(-6875 3200);
WIRE 16 -1 (-6550 3200)(-6550 3550);
WIRE 16 -1 (-5825 3550)(-6550 3550);
FORCEPROP 2 LAST SIG_NAME PVDD18_S5_P1_VCC
J 0
(-6260 3575);
DISPLAY 0.489362 (-6260 3575);
FORCEPROP 2 LASTPROP $XRERR UNIQUE?
J 0
(-6500 3575);
DISPLAY 0.638298 (-6500 3575);
PAINT MONO (-6500 3575);
DISPLAY INVISIBLE (-6500 3575);
WIRE 16 -1 (-6375 3200)(-5825 3200);
WIRE 16 -1 (-6375 3075)(-6375 3200);
FORCEPROP 2 LAST SIG_NAME PVDD18_S5_P1_CS
J 0
(-6235 3225);
DISPLAY 0.489362 (-6235 3225);
FORCEPROP 2 LASTPROP $XRERR UNIQUE?
J 0
(-6475 3225);
DISPLAY 0.638298 (-6475 3225);
PAINT MONO (-6475 3225);
DISPLAY INVISIBLE (-6475 3225);
DOT 1 (-2450 4000);
DOT 1 (-3775 4000);
DOT 1 (-8750 4775);
DOT 1 (-7725 4000);
DOT 1 (-6875 3200);
DOT 1 (-4875 3150);
DOT 1 (-4700 3300);
DOT 1 (-6325 4775);
DOT 1 (-6000 4500);
DOT 1 (-3875 2950);
DOT 1 (-3300 2500);
DOT 1 (-4000 3300);
DOT 1 (-3650 3550);
DOT 1 (-3875 3550);
DOT 1 (-2750 2500);
DOT 1 (-2750 2750);
DOT 1 (-2925 3550);
DOT 1 (-2750 3550);
DOT 1 (-2025 3500);
DOT 1 (-1825 3500);
DOT 1 (-1575 3500);
DOT 1 (-1825 4000);
DOT 1 (-1575 4000);
DOT 1 (-1250 3500);
DOT 1 (-975 3500);
DOT 1 (-1250 4000);
DOT 1 (-975 4000);
DOT 1 (-600 3500);
DOT 1 (-600 3925);
DOT 1 (-600 4000);
DOT 1 (50 4000);
DOT 1 (-4375 4500);
DOT 1 (-2025 4000);
DOT 1 (-2375 4500);
DOT 1 (-6575 4775);
DOT 1 (-6575 4328);
DOT 1 (-6825 4775);
DOT 1 (-6825 4328);
DOT 1 (-7150 4775);
DOT 1 (-7525 4775);
DOT 1 (-7525 4328);
DOT 1 (-7750 4328);
DOT 1 (-7850 4775);
DOT 1 (-7150 4328);
FORCENOTE
FSW=600KHZ
(-8125 3425) 0;
DISPLAY LEFT (-8125 3425);
DISPLAY 1.276596 (-8125 3425);
PAINT WHITE (-8125 3425);
FORCENOTE
1ST AL008633005/MPQ8633BGLE-C838-Z/MPS
(-8525 2025) 0;
DISPLAY LEFT (-8525 2025);
DISPLAY 1.021277 (-8525 2025);
PAINT WHITE (-8525 2025);
FORCENOTE
BOM NOTE
(-8525 2175) 0;
DISPLAY LEFT (-8525 2175);
DISPLAY 1.276596 (-8525 2175);
PAINT WHITE (-8525 2175);
FORCENOTE
FCCM
(-8125 3525) 0;
DISPLAY LEFT (-8125 3525);
DISPLAY 1.276596 (-8125 3525);
PAINT WHITE (-8125 3525);
FORCENOTE
MAX LOAD STEP=2.5A
(-1175 6400) 0;
DISPLAY LEFT (-1175 6400);
DISPLAY 0.936170 (-1175 6400);
PAINT WHITE (-1175 6400);
FORCENOTE
WORK FREQUENCY=600KHZ
(-1175 6250) 0;
DISPLAY LEFT (-1175 6250);
DISPLAY 0.936170 (-1175 6250);
PAINT WHITE (-1175 6250);
FORCENOTE
IRM REV1.09
(-1175 6100) 0;
DISPLAY LEFT (-1175 6100);
DISPLAY 0.936170 (-1175 6100);
PAINT WHITE (-1175 6100);
FORCENOTE
EFFICIENCY > 85% @TDC
(-1175 6175) 0;
DISPLAY LEFT (-1175 6175);
DISPLAY 0.936170 (-1175 6175);
PAINT WHITE (-1175 6175);
FORCENOTE
MAX LOAD RELEASE=2.5A
(-1175 6325) 0;
DISPLAY LEFT (-1175 6325);
DISPLAY 0.936170 (-1175 6325);
PAINT WHITE (-1175 6325);
FORCENOTE
AC =+/-30MV
(-1175 6700) 0;
DISPLAY LEFT (-1175 6700);
DISPLAY 0.936170 (-1175 6700);
PAINT WHITE (-1175 6700);
FORCENOTE
DC =1.76-1.84V
(-1175 6775) 0;
DISPLAY LEFT (-1175 6775);
DISPLAY 0.936170 (-1175 6775);
PAINT WHITE (-1175 6775);
FORCENOTE
OUTPUT VOLTAGE=1.8V
(-1175 6850) 0;
DISPLAY LEFT (-1175 6850);
DISPLAY 0.936170 (-1175 6850);
PAINT WHITE (-1175 6850);
FORCENOTE
OCP=15A (EDC*1.2)
(-1175 6475) 0;
DISPLAY LEFT (-1175 6475);
DISPLAY 0.936170 (-1175 6475);
PAINT WHITE (-1175 6475);
FORCENOTE
2ND=CV-10I0MZ00
(-3075 4050) 0;
DISPLAY LEFT (-3075 4050);
DISPLAY 0.638298 (-3075 4050);
PAINT WHITE (-3075 4050);
FORCENOTE
PCMC104T-1R0MN
(-3075 4250) 0;
DISPLAY LEFT (-3075 4250);
DISPLAY 0.638298 (-3075 4250);
PAINT WHITE (-3075 4250);
FORCENOTE
ISAT:25A@100C
(-3075 4200) 0;
DISPLAY LEFT (-3075 4200);
DISPLAY 0.638298 (-3075 4200);
PAINT WHITE (-3075 4200);
FORCENOTE
DCR=3.3M OHM
(-3075 4100) 0;
DISPLAY LEFT (-3075 4100);
DISPLAY 0.638298 (-3075 4100);
PAINT WHITE (-3075 4100);
FORCENOTE
10*10*4
(-3075 4150) 0;
DISPLAY LEFT (-3075 4150);
DISPLAY 0.638298 (-3075 4150);
PAINT WHITE (-3075 4150);
FORCENOTE
RA
(-3300 3675) 0;
DISPLAY LEFT (-3300 3675);
DISPLAY 1.021277 (-3300 3675);
PAINT WHITE (-3300 3675);
FORCENOTE
DCR=5M OHM
(-8625 4650) 0;
DISPLAY LEFT (-8625 4650);
DISPLAY 0.808511 (-8625 4650);
PAINT WHITE (-8625 4650);
FORCENOTE
PVDD18_S5_P1
(-5700 6025) 0;
DISPLAY LEFT (-5700 6025);
DISPLAY 3.148936 (-5700 6025);
PAINT WHITE (-5700 6025);
FORCENOTE
RB
(-3975 3325) 0;
DISPLAY LEFT (-3975 3325);
DISPLAY 1.021277 (-3975 3325);
PAINT WHITE (-3975 3325);
FORCENOTE
NEAR CPU SIDE
(-2425 2150) 0;
DISPLAY LEFT (-2425 2150);
DISPLAY 1.021277 (-2425 2150);
PAINT GREEN (-2425 2150);
FORCENOTE
TRACE SPACING = 5MIL
(-1325 2150) 0;
DISPLAY LEFT (-1325 2150);
DISPLAY 1.021277 (-1325 2150);
PAINT WHITE (-1325 2150);
FORCENOTE
TRACE WIDTH = 10MIL
(-1325 2225) 0;
DISPLAY LEFT (-1325 2225);
DISPLAY 1.021277 (-1325 2225);
PAINT WHITE (-1325 2225);
FORCENOTE
DIFFERENTIAL PAIR
(-1325 2300) 0;
DISPLAY LEFT (-1325 2300);
DISPLAY 1.021277 (-1325 2300);
PAINT WHITE (-1325 2300);
FORCENOTE
5.0*5.8
(-1100 3400) 0;
DISPLAY LEFT (-1100 3400);
DISPLAY 0.638298 (-1100 3400);
PAINT WHITE (-1100 3400);
FORCENOTE
ESR= 10 MOHM
(-1100 3450) 0;
DISPLAY LEFT (-1100 3450);
DISPLAY 0.638298 (-1100 3450);
PAINT WHITE (-1100 3450);
FORCENOTE
2ND=CC7390JMZ11
(-1100 3350) 0;
DISPLAY LEFT (-1100 3350);
DISPLAY 0.638298 (-1100 3350);
PAINT WHITE (-1100 3350);
FORCENOTE
PVDD18_S5_P1 SPECFICATION
(-1175 6975) 0;
DISPLAY LEFT (-1175 6975);
DISPLAY 1.276596 (-1175 6975);
PAINT WHITE (-1175 6975);
FORCENOTE
VOUT=0.6(1+RA/RB)=1.8V
(-4725 1900) 0;
DISPLAY LEFT (-4725 1900);
DISPLAY 2.000000 (-4725 1900);
PAINT WHITE (-4725 1900);
FORCENOTE
EDC=12A
(-1175 6550) 0;
DISPLAY LEFT (-1175 6550);
DISPLAY 0.936170 (-1175 6550);
PAINT WHITE (-1175 6550);
FORCENOTE
TDC=10A
(-1175 6625) 0;
DISPLAY LEFT (-1175 6625);
DISPLAY 0.936170 (-1175 6625);
PAINT WHITE (-1175 6625);
FORCENOTE
1ST
(-8525 1475) 0;
DISPLAY LEFT (-8525 1475);
DISPLAY 1.021277 (-8525 1475);
PAINT WHITE (-8525 1475);
FORCENOTE
2ND  NA
(-8525 1375) 0;
DISPLAY LEFT (-8525 1375);
DISPLAY 1.021277 (-8525 1375);
PAINT WHITE (-8525 1375);
FORCENOTE
PC64 CHANGE TO CH13306JB14
(-8325 1200) 0;
DISPLAY LEFT (-8325 1200);
DISPLAY 1.021277 (-8325 1200);
PAINT WHITE (-8325 1200);
FORCENOTE
3RD PC20 CHANGE TO CH5222KEB01
(-8525 1275) 0;
DISPLAY LEFT (-8525 1275);
DISPLAY 1.021277 (-8525 1275);
PAINT WHITE (-8525 1275);
FORCENOTE
BOM CHANGE R&C TABLE
(-8525 1625) 0;
DISPLAY LEFT (-8525 1625);
DISPLAY 1.276596 (-8525 1625);
PAINT WHITE (-8525 1625);
FORCENOTE
3RD AL000548007/TPS548B28RWWR/TI
(-8525 1875) 0;
DISPLAY LEFT (-8525 1875);
DISPLAY 1.021277 (-8525 1875);
PAINT WHITE (-8525 1875);
FORCENOTE
2ND AL053319002/RS53319LR/REEDSEMI
(-8525 1950) 0;
DISPLAY LEFT (-8525 1950);
DISPLAY 1.021277 (-8525 1950);
PAINT WHITE (-8525 1950);
FORCENOTE
3RD=CX000220000
(-8625 4550) 0;
DISPLAY LEFT (-8625 4550);
DISPLAY 0.808511 (-8625 4550);
PAINT WHITE (-8625 4550);
FORCENOTE
2ND=CX220Z06Z00
(-8625 4600) 0;
DISPLAY LEFT (-8625 4600);
DISPLAY 0.808511 (-8625 4600);
PAINT WHITE (-8625 4600);
FORCENOTE
IRATED=5A@125C
(-8625 4700) 0;
DISPLAY LEFT (-8625 4700);
DISPLAY 0.808511 (-8625 4700);
PAINT WHITE (-8625 4700);
QUIT
